FILE_TYPE = MACRO_DRAWING;
SET COLOR_WIRE YELLOW;
SET COLOR_PROP ORANGE;
SET COLOR_DOT WHITE;
SET COLOR_ARC YELLOW;
SET COLOR_BODY GREEN;
SET COLOR_NOTE PURPLE;
SET PROP_DISPLAY VALUE;
SET PAGE_NUMBER P279;
FORCEADD UNIVERSAL_GND..1
(-9000 7625);
FORCEPROP 3 LASTPIN (-9000 7675) SIG_NAME GND\g
J 0
(-8990 7685);
DISPLAY 0.659574 (-8990 7685);
PAINT MONO (-8990 7685);
DISPLAY INVISIBLE (-8990 7685);
FORCEPROP 1 LAST HDL_POWER GND
J 1
(-8975 7550);
DISPLAY 0.872340 (-8975 7550);
PAINT GREEN (-8975 7550);
DISPLAY INVISIBLE (-8975 7550);
FORCEPROP 2 LAST CDS_LIB logical_power
J 0
(-9000 7625);
DISPLAY INVISIBLE (-9000 7625);
FORCEPROP 1 LAST PATH I1
J 0
(-8925 7625);
DISPLAY 0.872340 (-8925 7625);
PAINT AQUA (-8925 7625);
DISPLAY INVISIBLE (-8925 7625);
FORCEADD Q_CAP..1
(-8500 8875);
FORCEPROP 1 LAST PART_NUMBER CH5222KEB01
J 0
(-8450 8700);
DISPLAY 0.617021 (-8450 8700);
PAINT BLUE (-8450 8700);
DISPLAY INVISIBLE (-8450 8700);
FORCEPROP 1 LAST MATERIAL X6S
J 0
(-8450 8800);
DISPLAY 0.617021 (-8450 8800);
PAINT SKYBLUE (-8450 8800);
FORCEPROP 1 LAST PACK_TYPE C0402
J 0
(-8450 8750);
DISPLAY 0.617021 (-8450 8750);
PAINT SKYBLUE (-8450 8750);
FORCEPROP 1 LAST VOLTAGE 10V
J 0
(-8450 8900);
DISPLAY 0.617021 (-8450 8900);
PAINT SKYBLUE (-8450 8900);
FORCEPROP 1 LAST VALUE 2.2UF
J 0
(-8450 8950);
DISPLAY 0.617021 (-8450 8950);
PAINT SKYBLUE (-8450 8950);
FORCEPROP 1 LAST TOLERANCE 10%
J 0
(-8450 8850);
DISPLAY 0.617021 (-8450 8850);
PAINT SKYBLUE (-8450 8850);
FORCEPROP 1 LAST LOCATION PC441
J 0
(-8450 9000);
DISPLAY 0.617021 (-8450 9000);
PAINT AQUA (-8450 9000);
FORCEPROP 1 LASTPIN (-8500 8975) $PN 1
J 0
(-8490 8955);
DISPLAY 0.617021 (-8490 8955);
PAINT MONO (-8490 8955);
FORCEPROP 1 LASTPIN (-8500 8775) $PN 2
J 0
(-8490 8755);
DISPLAY 0.617021 (-8490 8755);
PAINT MONO (-8490 8755);
FORCEPROP 2 LAST CDS_LIB pure_quanta
J 0
(-8500 8875);
DISPLAY INVISIBLE (-8500 8875);
FORCEPROP 1 LAST PATH I10
J 0
(-8450 9025);
DISPLAY 0.978723 (-8450 9025);
PAINT WHITE (-8450 9025);
DISPLAY INVISIBLE (-8450 9025);
FORCEPROP 1 LAST LOCATION PC441
J 0
(-8450 9050);
DISPLAY 1.021277 (-8450 9050);
PAINT AQUA (-8450 9050);
DISPLAY INVISIBLE (-8450 9050);
FORCEPROP 0 LAST $SEC 1
J 0
(-8450 9050);
DISPLAY 0.680851 (-8450 9050);
PAINT MONO (-8450 9050);
DISPLAY INVISIBLE (-8450 9050);
FORCEPROP 0 LAST CDS_SEC 1
J 0
(-8450 9050);
DISPLAY 1.021277 (-8450 9050);
DISPLAY INVISIBLE (-8450 9050);
FORCEADD Q_RES..2
(-8500 9275);
FORCEPROP 1 LAST PART_NUMBER CS-2202FB01
J 0
(-8460 9150);
DISPLAY 0.617021 (-8460 9150);
PAINT BLUE (-8460 9150);
DISPLAY INVISIBLE (-8460 9150);
FORCEPROP 1 LAST PACK_TYPE 0402LF
J 0
(-8460 9100);
DISPLAY 0.617021 (-8460 9100);
PAINT SKYBLUE (-8460 9100);
FORCEPROP 1 LAST VALUE 2.2
J 0
(-8455 9350);
DISPLAY 0.617021 (-8455 9350);
PAINT SKYBLUE (-8455 9350);
FORCEPROP 1 LAST MATERIAL CHIP
J 0
(-8460 9200);
DISPLAY 0.617021 (-8460 9200);
PAINT SKYBLUE (-8460 9200);
FORCEPROP 1 LAST TOLERANCE 1%
J 0
(-8455 9300);
DISPLAY 0.617021 (-8455 9300);
PAINT SKYBLUE (-8455 9300);
FORCEPROP 1 LAST WATTAGE 1/16W
J 0
(-8460 9250);
DISPLAY 0.617021 (-8460 9250);
PAINT SKYBLUE (-8460 9250);
FORCEPROP 1 LAST LOCATION PR255
J 0
(-8455 9400);
DISPLAY 0.617021 (-8455 9400);
PAINT AQUA (-8455 9400);
FORCEPROP 1 LASTPIN (-8500 9375) $PN 1
J 0
(-8495 9337);
DISPLAY 0.617021 (-8495 9337);
PAINT MONO (-8495 9337);
FORCEPROP 1 LASTPIN (-8500 9175) $PN 2
J 0
(-8495 9185);
DISPLAY 0.617021 (-8495 9185);
PAINT MONO (-8495 9185);
FORCEPROP 2 LAST CDS_LIB pure_quanta
J 0
(-8500 9275);
DISPLAY INVISIBLE (-8500 9275);
FORCEPROP 1 LAST PATH I11
J 0
(-8450 9450);
DISPLAY 0.978723 (-8450 9450);
PAINT WHITE (-8450 9450);
DISPLAY INVISIBLE (-8450 9450);
FORCEPROP 1 LAST LOCATION PR255
J 0
(-8450 9450);
DISPLAY 1.021277 (-8450 9450);
PAINT AQUA (-8450 9450);
DISPLAY INVISIBLE (-8450 9450);
FORCEPROP 0 LAST $SEC 1
J 0
(-8450 9450);
DISPLAY 0.680851 (-8450 9450);
PAINT MONO (-8450 9450);
DISPLAY INVISIBLE (-8450 9450);
FORCEPROP 0 LAST CDS_SEC 1
J 0
(-8450 9450);
DISPLAY 1.021277 (-8450 9450);
DISPLAY INVISIBLE (-8450 9450);
FORCEADD UNIVERSAL_GND..1
(-7975 9100);
FORCEPROP 3 LASTPIN (-7975 9150) SIG_NAME GND\g
J 0
(-7965 9160);
DISPLAY 0.659574 (-7965 9160);
PAINT MONO (-7965 9160);
DISPLAY INVISIBLE (-7965 9160);
FORCEPROP 1 LAST HDL_POWER GND
J 1
(-7950 9025);
DISPLAY 0.872340 (-7950 9025);
PAINT GREEN (-7950 9025);
DISPLAY INVISIBLE (-7950 9025);
FORCEPROP 2 LAST CDS_LIB logical_power
J 0
(-7975 9100);
DISPLAY INVISIBLE (-7975 9100);
FORCEPROP 1 LAST PATH I12
J 0
(-7900 9100);
DISPLAY 0.872340 (-7900 9100);
PAINT AQUA (-7900 9100);
DISPLAY INVISIBLE (-7900 9100);
FORCEADD Q_CAP..1
(-7975 9300);
FORCEPROP 1 LAST PART_NUMBER CH5222KEB01
J 0
(-7925 9225);
DISPLAY 0.638298 (-7925 9225);
DISPLAY INVISIBLE (-7925 9225);
FORCEPROP 1 LAST PACK_TYPE C0402
J 0
(-7925 9175);
DISPLAY 0.638298 (-7925 9175);
FORCEPROP 1 LAST MATERIAL X6S
J 0
(-7925 9275);
DISPLAY 0.638298 (-7925 9275);
FORCEPROP 1 LAST TOLERANCE 10%
J 0
(-7925 9325);
DISPLAY 0.638298 (-7925 9325);
FORCEPROP 1 LAST VOLTAGE 10V
J 0
(-7925 9375);
DISPLAY 0.638298 (-7925 9375);
FORCEPROP 1 LAST VALUE 2.2UF
J 0
(-7925 9425);
DISPLAY 0.638298 (-7925 9425);
FORCEPROP 1 LAST LOCATION PC2949
J 0
(-7925 9475);
DISPLAY 0.638298 (-7925 9475);
FORCEPROP 1 LASTPIN (-7975 9400) $PN 1
J 0
(-7965 9380);
DISPLAY 0.787234 (-7965 9380);
PAINT MONO (-7965 9380);
FORCEPROP 1 LASTPIN (-7975 9200) $PN 2
J 0
(-7965 9180);
DISPLAY 0.787234 (-7965 9180);
PAINT MONO (-7965 9180);
FORCEPROP 2 LAST CDS_LIB pure_quanta
J 0
(-7975 9300);
DISPLAY INVISIBLE (-7975 9300);
FORCEPROP 1 LAST PATH I13
J 0
(-7925 9450);
DISPLAY 0.978723 (-7925 9450);
PAINT WHITE (-7925 9450);
DISPLAY INVISIBLE (-7925 9450);
FORCEPROP 0 LAST $SEC 1
J 0
(-7925 9525);
DISPLAY 0.680851 (-7925 9525);
PAINT MONO (-7925 9525);
DISPLAY INVISIBLE (-7925 9525);
FORCEPROP 0 LAST CDS_SEC 1
J 0
(-7925 9525);
DISPLAY 1.021277 (-7925 9525);
DISPLAY INVISIBLE (-7925 9525);
FORCEADD VCC15..1
(-8500 9725);
FORCEPROP 1 LAST HDL_POWER PVCCFA_EHV_CPU1_PVCC
J 1
(-8500 9775);
DISPLAY 0.617021 (-8500 9775);
PAINT GREEN (-8500 9775);
FORCEPROP 2 LAST CDS_LIB logical_power
J 0
(-8500 9725);
DISPLAY INVISIBLE (-8500 9725);
FORCEPROP 1 LAST PATH I14
J 0
(-8450 9750);
DISPLAY 0.872340 (-8450 9750);
PAINT AQUA (-8450 9750);
DISPLAY INVISIBLE (-8450 9750);
FORCEADD UNIVERSAL_GND..1
(-9000 10425);
FORCEPROP 3 LASTPIN (-9000 10475) SIG_NAME GND\g
J 0
(-8990 10485);
DISPLAY 0.659574 (-8990 10485);
PAINT MONO (-8990 10485);
DISPLAY INVISIBLE (-8990 10485);
FORCEPROP 1 LAST HDL_POWER GND
J 1
(-8975 10350);
DISPLAY 0.872340 (-8975 10350);
PAINT GREEN (-8975 10350);
DISPLAY INVISIBLE (-8975 10350);
FORCEPROP 2 LAST CDS_LIB logical_power
J 0
(-9000 10425);
DISPLAY INVISIBLE (-9000 10425);
FORCEPROP 1 LAST PATH I15
J 0
(-8925 10425);
DISPLAY 0.872340 (-8925 10425);
PAINT AQUA (-8925 10425);
DISPLAY INVISIBLE (-8925 10425);
FORCEADD Q_RES..2
R 2
(-9000 10650);
FORCEPROP 1 LAST PART_NUMBER CS28872FB01
J 2
(-9040 10525);
DISPLAY 0.617021 (-9040 10525);
PAINT BLUE (-9040 10525);
DISPLAY INVISIBLE (-9040 10525);
FORCEPROP 1 LAST VALUE 8.87K
J 2
(-9045 10725);
DISPLAY 0.617021 (-9045 10725);
PAINT SKYBLUE (-9045 10725);
FORCEPROP 1 LAST TOLERANCE 1%
J 2
(-9045 10675);
DISPLAY 0.617021 (-9045 10675);
PAINT SKYBLUE (-9045 10675);
FORCEPROP 1 LAST MATERIAL EMPTY
J 2
(-9040 10575);
DISPLAY 0.617021 (-9040 10575);
PAINT RED (-9040 10575);
FORCEPROP 1 LAST WATTAGE 1/16W
J 2
(-9040 10625);
DISPLAY 0.617021 (-9040 10625);
PAINT SKYBLUE (-9040 10625);
FORCEPROP 1 LAST PACK_TYPE 0402LF
J 2
(-9040 10475);
DISPLAY 0.617021 (-9040 10475);
PAINT SKYBLUE (-9040 10475);
FORCEPROP 1 LAST LOCATION PR1726
J 2
(-9045 10775);
DISPLAY 0.617021 (-9045 10775);
PAINT AQUA (-9045 10775);
FORCEPROP 1 LASTPIN (-9000 10750) $PN 1
J 2
(-9005 10712);
DISPLAY 0.617021 (-9005 10712);
PAINT MONO (-9005 10712);
FORCEPROP 1 LASTPIN (-9000 10550) $PN 2
J 2
(-9005 10560);
DISPLAY 0.617021 (-9005 10560);
PAINT MONO (-9005 10560);
FORCEPROP 2 LAST CDS_LIB pure_quanta
J 2
(-9000 10650);
DISPLAY INVISIBLE (-9000 10650);
FORCEPROP 1 LAST PATH I16
J 2
(-9050 10825);
DISPLAY 0.978723 (-9050 10825);
PAINT WHITE (-9050 10825);
DISPLAY INVISIBLE (-9050 10825);
FORCEPROP 0 LAST $SEC 1
J 0
(-9025 10800);
DISPLAY 0.680851 (-9025 10800);
PAINT MONO (-9025 10800);
DISPLAY INVISIBLE (-9025 10800);
FORCEPROP 0 LAST CDS_SEC 1
J 0
(-9025 10800);
DISPLAY 1.021277 (-9025 10800);
DISPLAY INVISIBLE (-9025 10800);
FORCEADD UNIVERSAL_GND..1
(-9150 10950);
FORCEPROP 3 LASTPIN (-9150 11000) SIG_NAME GND\g
J 0
(-9140 11010);
DISPLAY 0.659574 (-9140 11010);
PAINT MONO (-9140 11010);
DISPLAY INVISIBLE (-9140 11010);
FORCEPROP 1 LAST HDL_POWER GND
J 1
(-9125 10875);
DISPLAY 0.872340 (-9125 10875);
PAINT GREEN (-9125 10875);
DISPLAY INVISIBLE (-9125 10875);
FORCEPROP 2 LAST CDS_LIB logical_power
J 0
(-9150 10950);
PAINT MONO (-9150 10950);
DISPLAY INVISIBLE (-9150 10950);
FORCEPROP 1 LAST PATH I17
J 0
(-9075 10950);
DISPLAY 0.872340 (-9075 10950);
PAINT AQUA (-9075 10950);
DISPLAY INVISIBLE (-9075 10950);
FORCEADD OFFPAGE..1
(-8425 10625);
FORCEPROP 2 LAST $XR0 292 
J 0
(-8677 10625);
DISPLAY 0.638298 (-8677 10625);
PAINT MONO (-8677 10625);
FORCEPROP 1 LAST COMMENT_BODY TRUE
J 0
(-8300 10525);
DISPLAY 0.872340 (-8300 10525);
PAINT GREEN (-8300 10525);
DISPLAY INVISIBLE (-8300 10525);
FORCEPROP 1 LAST OFFPAGE TRUE
J 0
(-8100 10500);
DISPLAY 0.872340 (-8100 10500);
PAINT GREEN (-8100 10500);
DISPLAY INVISIBLE (-8100 10500);
FORCEPROP 2 LAST CDS_LIB standard
J 0
(-8425 10625);
DISPLAY INVISIBLE (-8425 10625);
FORCEPROP 2 LAST PATH I18
J 0
(-8675 10675);
DISPLAY 1.021277 (-8675 10675);
DISPLAY INVISIBLE (-8675 10675);
FORCEADD OFFPAGE..5
(-8425 10725);
FORCEPROP 2 LAST $XR1 292 
J 0
(-8830 10725);
DISPLAY 0.638298 (-8830 10725);
PAINT MONO (-8830 10725);
FORCEPROP 2 LAST $XR0 293 
J 0
(-8710 10725);
DISPLAY 0.638298 (-8710 10725);
PAINT MONO (-8710 10725);
FORCEPROP 1 LAST COMMENT_BODY TRUE
J 0
(-8325 10650);
DISPLAY 0.872340 (-8325 10650);
PAINT GREEN (-8325 10650);
DISPLAY INVISIBLE (-8325 10650);
FORCEPROP 1 LAST OFFPAGE TRUE
J 0
(-8100 10600);
DISPLAY 0.872340 (-8100 10600);
PAINT GREEN (-8100 10600);
DISPLAY INVISIBLE (-8100 10600);
FORCEPROP 2 LAST CDS_LIB standard
J 0
(-8425 10725);
DISPLAY INVISIBLE (-8425 10725);
FORCEPROP 2 LAST PATH I19
J 0
(-8700 10775);
DISPLAY 1.021277 (-8700 10775);
DISPLAY INVISIBLE (-8700 10775);
FORCEADD UNIVERSAL_GND..1
(-9150 8150);
FORCEPROP 3 LASTPIN (-9150 8200) SIG_NAME GND\g
J 0
(-9140 8210);
DISPLAY 0.659574 (-9140 8210);
PAINT MONO (-9140 8210);
DISPLAY INVISIBLE (-9140 8210);
FORCEPROP 1 LAST HDL_POWER GND
J 1
(-9125 8075);
DISPLAY 0.872340 (-9125 8075);
PAINT GREEN (-9125 8075);
DISPLAY INVISIBLE (-9125 8075);
FORCEPROP 2 LAST CDS_LIB logical_power
J 0
(-9150 8150);
PAINT MONO (-9150 8150);
DISPLAY INVISIBLE (-9150 8150);
FORCEPROP 1 LAST PATH I2
J 0
(-9075 8150);
DISPLAY 0.872340 (-9075 8150);
PAINT AQUA (-9075 8150);
DISPLAY INVISIBLE (-9075 8150);
FORCEADD Q_CAP..2
(-8325 11050);
FORCEPROP 1 LAST PART_NUMBER CH4104K1B00
J 1
(-8100 11000);
DISPLAY 0.617021 (-8100 11000);
PAINT BLUE (-8100 11000);
DISPLAY INVISIBLE (-8100 11000);
FORCEPROP 1 LAST PACK_TYPE 0402
J 1
(-8125 11050);
DISPLAY 0.617021 (-8125 11050);
PAINT SKYBLUE (-8125 11050);
FORCEPROP 1 LAST TOLERANCE 10%
J 2
(-7850 11050);
DISPLAY 0.617021 (-7850 11050);
PAINT SKYBLUE (-7850 11050);
FORCEPROP 1 LAST MATERIAL X7R
J 0
(-8050 11050);
DISPLAY 0.617021 (-8050 11050);
PAINT SKYBLUE (-8050 11050);
FORCEPROP 1 LAST VOLTAGE 25V
J 0
(-8450 11000);
DISPLAY 0.617021 (-8450 11000);
PAINT SKYBLUE (-8450 11000);
FORCEPROP 1 LAST VALUE 0.1UF
J 2
(-8500 11000);
DISPLAY 0.617021 (-8500 11000);
PAINT SKYBLUE (-8500 11000);
FORCEPROP 1 LAST LOCATION PC1364
J 1
(-8525 11050);
DISPLAY 0.617021 (-8525 11050);
PAINT AQUA (-8525 11050);
FORCEPROP 1 LASTPIN (-8425 11050) $PN 1
J 0
(-8435 11065);
DISPLAY 0.617021 (-8435 11065);
FORCEPROP 1 LASTPIN (-8225 11050) $PN 2
J 0
(-8240 11065);
DISPLAY 0.617021 (-8240 11065);
FORCEPROP 2 LAST CDS_LIB pure_quanta
J 0
(-8325 11050);
PAINT MONO (-8325 11050);
DISPLAY INVISIBLE (-8325 11050);
FORCEPROP 1 LAST PATH I20
J 0
(-8325 11250);
DISPLAY 0.978723 (-8325 11250);
PAINT WHITE (-8325 11250);
DISPLAY INVISIBLE (-8325 11250);
FORCEPROP 2 LAST $SEC 1
J 0
(-8325 11300);
DISPLAY 0.680851 (-8325 11300);
PAINT MONO (-8325 11300);
DISPLAY INVISIBLE (-8325 11300);
FORCEPROP 2 LAST CDS_SEC 1
J 0
(-8325 11300);
DISPLAY 1.021277 (-8325 11300);
DISPLAY INVISIBLE (-8325 11300);
FORCEADD OFFPAGE..5
(-8425 11225);
FORCEPROP 2 LAST $XR0 292 
J 0
(-8710 11225);
DISPLAY 0.638298 (-8710 11225);
PAINT MONO (-8710 11225);
FORCEPROP 1 LAST COMMENT_BODY TRUE
J 0
(-8325 11150);
DISPLAY 0.872340 (-8325 11150);
PAINT GREEN (-8325 11150);
DISPLAY INVISIBLE (-8325 11150);
FORCEPROP 1 LAST OFFPAGE TRUE
J 0
(-8100 11100);
DISPLAY 0.872340 (-8100 11100);
PAINT GREEN (-8100 11100);
DISPLAY INVISIBLE (-8100 11100);
FORCEPROP 2 LAST CDS_LIB standard
J 0
(-8425 11225);
DISPLAY INVISIBLE (-8425 11225);
FORCEPROP 2 LAST PATH I21
J 0
(-8700 11275);
DISPLAY 1.021277 (-8700 11275);
DISPLAY INVISIBLE (-8700 11275);
FORCEADD OFFPAGE..1
(-8425 11125);
FORCEPROP 2 LAST $XR2 294 
J 0
(-8917 11125);
DISPLAY 0.638298 (-8917 11125);
PAINT MONO (-8917 11125);
FORCEPROP 2 LAST $XR1 293 
J 0
(-8797 11125);
DISPLAY 0.638298 (-8797 11125);
PAINT MONO (-8797 11125);
FORCEPROP 2 LAST $XR0 292 
J 0
(-8677 11125);
DISPLAY 0.638298 (-8677 11125);
PAINT MONO (-8677 11125);
FORCEPROP 1 LAST COMMENT_BODY TRUE
J 0
(-8300 11025);
DISPLAY 0.872340 (-8300 11025);
PAINT GREEN (-8300 11025);
DISPLAY INVISIBLE (-8300 11025);
FORCEPROP 1 LAST OFFPAGE TRUE
J 0
(-8100 11000);
DISPLAY 0.872340 (-8100 11000);
PAINT GREEN (-8100 11000);
DISPLAY INVISIBLE (-8100 11000);
FORCEPROP 2 LAST CDS_LIB standard
J 0
(-8425 11125);
DISPLAY INVISIBLE (-8425 11125);
FORCEPROP 2 LAST PATH I22
J 0
(-8675 11175);
DISPLAY 1.021277 (-8675 11175);
DISPLAY INVISIBLE (-8675 11175);
FORCEADD UNIVERSAL_GND..1
(-8500 11425);
FORCEPROP 3 LASTPIN (-8500 11475) SIG_NAME GND\g
J 0
(-8490 11485);
DISPLAY 0.659574 (-8490 11485);
PAINT MONO (-8490 11485);
DISPLAY INVISIBLE (-8490 11485);
FORCEPROP 1 LAST HDL_POWER GND
J 1
(-8475 11350);
DISPLAY 0.872340 (-8475 11350);
PAINT GREEN (-8475 11350);
DISPLAY INVISIBLE (-8475 11350);
FORCEPROP 2 LAST CDS_LIB logical_power
J 0
(-8500 11425);
PAINT MONO (-8500 11425);
DISPLAY INVISIBLE (-8500 11425);
FORCEPROP 1 LAST PATH I23
J 0
(-8425 11425);
DISPLAY 0.872340 (-8425 11425);
PAINT AQUA (-8425 11425);
DISPLAY INVISIBLE (-8425 11425);
FORCEADD Q_CAP..1
(-8500 11675);
FORCEPROP 1 LAST PART_NUMBER CH5222KEB01
J 0
(-8450 11500);
DISPLAY 0.617021 (-8450 11500);
PAINT BLUE (-8450 11500);
DISPLAY INVISIBLE (-8450 11500);
FORCEPROP 1 LAST PACK_TYPE C0402
J 0
(-8450 11550);
DISPLAY 0.617021 (-8450 11550);
PAINT SKYBLUE (-8450 11550);
FORCEPROP 1 LAST TOLERANCE 10%
J 0
(-8450 11650);
DISPLAY 0.617021 (-8450 11650);
PAINT SKYBLUE (-8450 11650);
FORCEPROP 1 LAST VALUE 2.2UF
J 0
(-8450 11750);
DISPLAY 0.617021 (-8450 11750);
PAINT SKYBLUE (-8450 11750);
FORCEPROP 1 LAST VOLTAGE 10V
J 0
(-8450 11700);
DISPLAY 0.617021 (-8450 11700);
PAINT SKYBLUE (-8450 11700);
FORCEPROP 1 LAST MATERIAL X6S
J 0
(-8450 11600);
DISPLAY 0.617021 (-8450 11600);
PAINT SKYBLUE (-8450 11600);
FORCEPROP 1 LAST LOCATION PC440
J 0
(-8450 11800);
DISPLAY 0.617021 (-8450 11800);
PAINT AQUA (-8450 11800);
FORCEPROP 1 LASTPIN (-8500 11775) $PN 1
J 0
(-8490 11755);
DISPLAY 0.617021 (-8490 11755);
PAINT MONO (-8490 11755);
FORCEPROP 1 LASTPIN (-8500 11575) $PN 2
J 0
(-8490 11555);
DISPLAY 0.617021 (-8490 11555);
PAINT MONO (-8490 11555);
FORCEPROP 2 LAST CDS_LIB pure_quanta
J 0
(-8500 11675);
DISPLAY INVISIBLE (-8500 11675);
FORCEPROP 1 LAST PATH I24
J 0
(-8450 11825);
DISPLAY 0.978723 (-8450 11825);
PAINT WHITE (-8450 11825);
DISPLAY INVISIBLE (-8450 11825);
FORCEPROP 1 LAST LOCATION PC440
J 0
(-8450 11850);
DISPLAY 1.021277 (-8450 11850);
PAINT AQUA (-8450 11850);
DISPLAY INVISIBLE (-8450 11850);
FORCEPROP 0 LAST $SEC 1
J 0
(-8450 11850);
DISPLAY 0.680851 (-8450 11850);
PAINT MONO (-8450 11850);
DISPLAY INVISIBLE (-8450 11850);
FORCEPROP 0 LAST CDS_SEC 1
J 0
(-8450 11850);
DISPLAY 1.021277 (-8450 11850);
DISPLAY INVISIBLE (-8450 11850);
FORCEADD Q_RES..2
(-8500 12075);
FORCEPROP 1 LAST PART_NUMBER CS-2202FB01
J 0
(-8460 11950);
DISPLAY 0.617021 (-8460 11950);
PAINT BLUE (-8460 11950);
DISPLAY INVISIBLE (-8460 11950);
FORCEPROP 1 LAST WATTAGE 1/16W
J 0
(-8460 12050);
DISPLAY 0.617021 (-8460 12050);
PAINT SKYBLUE (-8460 12050);
FORCEPROP 1 LAST MATERIAL CHIP
J 0
(-8460 12000);
DISPLAY 0.617021 (-8460 12000);
PAINT SKYBLUE (-8460 12000);
FORCEPROP 1 LAST TOLERANCE 1%
J 0
(-8455 12100);
DISPLAY 0.617021 (-8455 12100);
PAINT SKYBLUE (-8455 12100);
FORCEPROP 1 LAST PACK_TYPE 0402LF
J 0
(-8460 11900);
DISPLAY 0.617021 (-8460 11900);
PAINT SKYBLUE (-8460 11900);
FORCEPROP 1 LAST VALUE 2.2
J 0
(-8455 12150);
DISPLAY 0.617021 (-8455 12150);
PAINT SKYBLUE (-8455 12150);
FORCEPROP 1 LAST LOCATION PR254
J 0
(-8455 12200);
DISPLAY 0.617021 (-8455 12200);
PAINT AQUA (-8455 12200);
FORCEPROP 1 LASTPIN (-8500 12175) $PN 1
J 0
(-8495 12137);
DISPLAY 0.617021 (-8495 12137);
PAINT MONO (-8495 12137);
FORCEPROP 1 LASTPIN (-8500 11975) $PN 2
J 0
(-8495 11985);
DISPLAY 0.617021 (-8495 11985);
PAINT MONO (-8495 11985);
FORCEPROP 2 LAST CDS_LIB pure_quanta
J 0
(-8500 12075);
DISPLAY INVISIBLE (-8500 12075);
FORCEPROP 1 LAST PATH I25
J 0
(-8450 12250);
DISPLAY 0.978723 (-8450 12250);
PAINT WHITE (-8450 12250);
DISPLAY INVISIBLE (-8450 12250);
FORCEPROP 1 LAST LOCATION PR254
J 0
(-8450 12250);
DISPLAY 1.021277 (-8450 12250);
PAINT AQUA (-8450 12250);
DISPLAY INVISIBLE (-8450 12250);
FORCEPROP 0 LAST $SEC 1
J 0
(-8450 12250);
DISPLAY 0.680851 (-8450 12250);
PAINT MONO (-8450 12250);
DISPLAY INVISIBLE (-8450 12250);
FORCEPROP 0 LAST CDS_SEC 1
J 0
(-8450 12250);
DISPLAY 1.021277 (-8450 12250);
DISPLAY INVISIBLE (-8450 12250);
FORCEADD Q_CAP..1
(-7925 12050);
FORCEPROP 1 LAST PART_NUMBER CH5222KEB01
J 0
(-7875 11975);
DISPLAY 0.638298 (-7875 11975);
DISPLAY INVISIBLE (-7875 11975);
FORCEPROP 1 LAST VOLTAGE 10V
J 0
(-7875 12125);
DISPLAY 0.638298 (-7875 12125);
FORCEPROP 1 LAST VALUE 2.2UF
J 0
(-7875 12175);
DISPLAY 0.638298 (-7875 12175);
FORCEPROP 1 LAST PACK_TYPE C0402
J 0
(-7875 11925);
DISPLAY 0.638298 (-7875 11925);
FORCEPROP 1 LAST TOLERANCE 10%
J 0
(-7875 12075);
DISPLAY 0.638298 (-7875 12075);
FORCEPROP 1 LAST MATERIAL X6S
J 0
(-7875 12025);
DISPLAY 0.638298 (-7875 12025);
FORCEPROP 1 LAST LOCATION PC2950
J 0
(-7875 12225);
DISPLAY 0.638298 (-7875 12225);
FORCEPROP 1 LASTPIN (-7925 12150) $PN 1
J 0
(-7915 12130);
DISPLAY 0.787234 (-7915 12130);
PAINT MONO (-7915 12130);
FORCEPROP 1 LASTPIN (-7925 11950) $PN 2
J 0
(-7915 11930);
DISPLAY 0.787234 (-7915 11930);
PAINT MONO (-7915 11930);
FORCEPROP 2 LAST CDS_LIB pure_quanta
J 0
(-7925 12050);
DISPLAY INVISIBLE (-7925 12050);
FORCEPROP 1 LAST PATH I26
J 0
(-7875 12200);
DISPLAY 0.978723 (-7875 12200);
PAINT WHITE (-7875 12200);
DISPLAY INVISIBLE (-7875 12200);
FORCEPROP 0 LAST $SEC 1
J 0
(-7875 12275);
DISPLAY 0.680851 (-7875 12275);
PAINT MONO (-7875 12275);
DISPLAY INVISIBLE (-7875 12275);
FORCEPROP 0 LAST CDS_SEC 1
J 0
(-7875 12275);
DISPLAY 1.021277 (-7875 12275);
DISPLAY INVISIBLE (-7875 12275);
FORCEADD UNIVERSAL_GND..1
(-7925 11875);
FORCEPROP 3 LASTPIN (-7925 11925) SIG_NAME GND\g
J 0
(-7915 11935);
DISPLAY 0.659574 (-7915 11935);
PAINT MONO (-7915 11935);
DISPLAY INVISIBLE (-7915 11935);
FORCEPROP 1 LAST HDL_POWER GND
J 1
(-7900 11800);
DISPLAY 0.872340 (-7900 11800);
PAINT GREEN (-7900 11800);
DISPLAY INVISIBLE (-7900 11800);
FORCEPROP 2 LAST CDS_LIB logical_power
J 0
(-7925 11875);
DISPLAY INVISIBLE (-7925 11875);
FORCEPROP 1 LAST PATH I27
J 0
(-7850 11875);
DISPLAY 0.872340 (-7850 11875);
PAINT AQUA (-7850 11875);
DISPLAY INVISIBLE (-7850 11875);
FORCEADD VCC15..1
(-8500 12475);
FORCEPROP 1 LAST HDL_POWER PVCCFA_EHV_CPU1_PVCC
J 1
(-8500 12525);
DISPLAY 0.617021 (-8500 12525);
PAINT GREEN (-8500 12525);
FORCEPROP 2 LAST CDS_LIB logical_power
J 0
(-8500 12475);
DISPLAY INVISIBLE (-8500 12475);
FORCEPROP 1 LAST PATH I28
J 0
(-8450 12500);
DISPLAY 0.872340 (-8450 12500);
PAINT AQUA (-8450 12500);
DISPLAY INVISIBLE (-8450 12500);
FORCEADD ISL99390FRZTR5935..1
(-6975 8425);
FORCEPROP 1 LAST PART_NUMBER AL099390004
J 0
(-7275 9225);
DISPLAY 0.723404 (-7275 9225);
PAINT GREEN (-7275 9225);
DISPLAY INVISIBLE (-7275 9225);
FORCEPROP 1 LAST MATERIAL IC
J 0
(-7275 9150);
DISPLAY 0.723404 (-7275 9150);
PAINT GREEN (-7275 9150);
FORCEPROP 2 LAST PART_TYPE SMLF
J 0
(-7250 9525);
DISPLAY 0.808511 (-7250 9525);
FORCEPROP 2 LAST VALUE ISL99390FRZ-TR5935
J 0
(-7250 9450);
DISPLAY 0.617021 (-7250 9450);
PAINT SKYBLUE (-7250 9450);
FORCEPROP 1 LAST LOCATION PU51_P1_2
J 0
(-7275 9300);
DISPLAY 0.723404 (-7275 9300);
PAINT GREEN (-7275 9300);
FORCEPROP 0 LASTPIN (-6575 7975) $PN 2
J 0
(-6565 7985);
DISPLAY 0.680851 (-6565 7985);
PAINT MONO (-6565 7985);
FORCEPROP 0 LASTPIN (-6575 8775) $PN 33
J 0
(-6565 8785);
DISPLAY 0.680851 (-6565 8785);
PAINT MONO (-6565 8785);
FORCEPROP 0 LASTPIN (-7425 8175) $PN 31
J 2
(-7435 8185);
DISPLAY 0.680851 (-7435 8185);
PAINT MONO (-7435 8185);
FORCEPROP 0 LASTPIN (-7425 8575) $PN 35
J 2
(-7435 8585);
DISPLAY 0.680851 (-7435 8585);
PAINT MONO (-7435 8585);
FORCEPROP 0 LASTPIN (-6575 8125) $PN 6
J 0
(-6565 8135);
DISPLAY 0.680851 (-6565 8135);
PAINT MONO (-6565 8135);
FORCEPROP 0 LASTPIN (-6575 8075) $PN 41
J 0
(-6565 8085);
DISPLAY 0.680851 (-6565 8085);
PAINT MONO (-6565 8085);
FORCEPROP 0 LASTPIN (-7425 8425) $PN 38
J 2
(-7435 8435);
DISPLAY 0.680851 (-7435 8435);
PAINT MONO (-7435 8435);
FORCEPROP 0 LASTPIN (-7425 8125) $PN 37
J 2
(-7435 8135);
DISPLAY 0.680851 (-7435 8135);
PAINT MONO (-7435 8135);
FORCEPROP 0 LASTPIN (-6575 7925) $PN 5
J 0
(-6565 7935);
DISPLAY 0.680851 (-6565 7935);
PAINT MONO (-6565 7935);
FORCEPROP 0 LASTPIN (-6575 7875) $PN 7_9-20_24
J 0
(-6565 7885);
DISPLAY 0.680851 (-6565 7885);
PAINT MONO (-6565 7885);
FORCEPROP 0 LASTPIN (-6575 7825) $PN 40
J 0
(-6565 7835);
DISPLAY 0.680851 (-6565 7835);
PAINT MONO (-6565 7835);
FORCEPROP 0 LASTPIN (-6575 8525) $PN 32
J 0
(-6565 8535);
DISPLAY 0.680851 (-6565 8535);
PAINT MONO (-6565 8535);
FORCEPROP 0 LASTPIN (-7425 9075) $PN 4
J 2
(-7435 9085);
DISPLAY 0.680851 (-7435 9085);
PAINT MONO (-7435 9085);
FORCEPROP 0 LASTPIN (-7425 7825) $PN 34
J 2
(-7435 7835);
DISPLAY 0.680851 (-7435 7835);
PAINT MONO (-7435 7835);
FORCEPROP 0 LASTPIN (-7425 8325) $PN 39
J 2
(-7435 8335);
DISPLAY 0.680851 (-7435 8335);
PAINT MONO (-7435 8335);
FORCEPROP 0 LASTPIN (-6575 8425) $PN 10_19
J 0
(-6565 8435);
DISPLAY 0.680851 (-6565 8435);
PAINT MONO (-6565 8435);
FORCEPROP 0 LASTPIN (-7425 7925) $PN 36
J 2
(-7435 7935);
DISPLAY 0.680851 (-7435 7935);
PAINT MONO (-7435 7935);
FORCEPROP 0 LASTPIN (-7425 8775) $PN 3
J 2
(-7435 8785);
DISPLAY 0.680851 (-7435 8785);
PAINT MONO (-7435 8785);
FORCEPROP 0 LASTPIN (-6575 9075) $PN 25_29
J 0
(-6565 9085);
DISPLAY 0.680851 (-6565 9085);
PAINT MONO (-6565 9085);
FORCEPROP 0 LASTPIN (-6575 9025) $PN 30
J 0
(-6565 9035);
DISPLAY 0.680851 (-6565 9035);
PAINT MONO (-6565 9035);
FORCEPROP 0 LASTPIN (-6575 8175) $PN 1
J 0
(-6565 8185);
DISPLAY 0.680851 (-6565 8185);
PAINT MONO (-6565 8185);
FORCEPROP 1 LAST CDS_LMAN_SYM_OUTLINE -300,700,250,-650
J 0
(-6975 8425);
DISPLAY 0.468085 (-6975 8425);
PAINT GREEN (-6975 8425);
DISPLAY INVISIBLE (-6975 8425);
FORCEPROP 1 LAST NEEDS_NO_SIZE TRUE
J 0
(-6975 8425);
DISPLAY 0.723404 (-6975 8425);
PAINT GREEN (-6975 8425);
DISPLAY INVISIBLE (-6975 8425);
FORCEPROP 2 LAST CDS_LIB pure_quanta
J 0
(-6975 8425);
DISPLAY INVISIBLE (-6975 8425);
FORCEPROP 1 LAST PATH I29
J 0
(-6975 8425);
DISPLAY 0.723404 (-6975 8425);
PAINT GREEN (-6975 8425);
DISPLAY INVISIBLE (-6975 8425);
FORCEPROP 0 LAST $SEC 1
J 0
(-7250 9575);
DISPLAY 0.680851 (-7250 9575);
PAINT MONO (-7250 9575);
DISPLAY INVISIBLE (-7250 9575);
FORCEPROP 0 LAST CDS_SEC 1
J 0
(-7250 9575);
DISPLAY 1.021277 (-7250 9575);
DISPLAY INVISIBLE (-7250 9575);
FORCEADD Q_RES..2
R 2
(-9000 7850);
FORCEPROP 1 LAST PART_NUMBER CS28872FB01
J 2
(-9040 7725);
DISPLAY 0.617021 (-9040 7725);
PAINT BLUE (-9040 7725);
DISPLAY INVISIBLE (-9040 7725);
FORCEPROP 1 LAST PACK_TYPE 0402LF
J 2
(-9040 7675);
DISPLAY 0.617021 (-9040 7675);
PAINT SKYBLUE (-9040 7675);
FORCEPROP 1 LAST VALUE 8.87K
J 2
(-9045 7925);
DISPLAY 0.617021 (-9045 7925);
PAINT SKYBLUE (-9045 7925);
FORCEPROP 1 LAST TOLERANCE 1%
J 2
(-9045 7875);
DISPLAY 0.617021 (-9045 7875);
PAINT SKYBLUE (-9045 7875);
FORCEPROP 1 LAST MATERIAL EMPTY
J 2
(-9040 7775);
DISPLAY 0.617021 (-9040 7775);
PAINT RED (-9040 7775);
FORCEPROP 1 LAST WATTAGE 1/16W
J 2
(-9040 7825);
DISPLAY 0.617021 (-9040 7825);
PAINT SKYBLUE (-9040 7825);
FORCEPROP 1 LAST LOCATION PR1727
J 2
(-9045 7975);
DISPLAY 0.617021 (-9045 7975);
PAINT AQUA (-9045 7975);
FORCEPROP 1 LASTPIN (-9000 7950) $PN 1
J 2
(-9005 7912);
DISPLAY 0.617021 (-9005 7912);
PAINT MONO (-9005 7912);
FORCEPROP 1 LASTPIN (-9000 7750) $PN 2
J 2
(-9005 7760);
DISPLAY 0.617021 (-9005 7760);
PAINT MONO (-9005 7760);
FORCEPROP 2 LAST CDS_LIB pure_quanta
J 2
(-9000 7850);
DISPLAY INVISIBLE (-9000 7850);
FORCEPROP 1 LAST PATH I3
J 2
(-9050 8025);
DISPLAY 0.978723 (-9050 8025);
PAINT WHITE (-9050 8025);
DISPLAY INVISIBLE (-9050 8025);
FORCEPROP 0 LAST $SEC 1
J 0
(-9025 8000);
DISPLAY 0.680851 (-9025 8000);
PAINT MONO (-9025 8000);
DISPLAY INVISIBLE (-9025 8000);
FORCEPROP 0 LAST CDS_SEC 1
J 0
(-9025 8000);
DISPLAY 1.021277 (-9025 8000);
DISPLAY INVISIBLE (-9025 8000);
FORCEADD UNIVERSAL_GND..1
(-6325 7700);
FORCEPROP 3 LASTPIN (-6325 7750) SIG_NAME GND\g
J 0
(-6315 7760);
DISPLAY 0.659574 (-6315 7760);
PAINT MONO (-6315 7760);
DISPLAY INVISIBLE (-6315 7760);
FORCEPROP 1 LAST HDL_POWER GND
J 1
(-6300 7625);
DISPLAY 0.872340 (-6300 7625);
PAINT GREEN (-6300 7625);
DISPLAY INVISIBLE (-6300 7625);
FORCEPROP 2 LAST CDS_LIB logical_power
J 0
(-6325 7700);
PAINT MONO (-6325 7700);
DISPLAY INVISIBLE (-6325 7700);
FORCEPROP 1 LAST PATH I30
J 0
(-6250 7700);
DISPLAY 0.872340 (-6250 7700);
PAINT AQUA (-6250 7700);
DISPLAY INVISIBLE (-6250 7700);
FORCEADD Q_RES..1
(-5275 8175);
FORCEPROP 1 LAST PART_NUMBER CS00002JB13
J 0
(-5500 8000);
DISPLAY 0.617021 (-5500 8000);
PAINT BLUE (-5500 8000);
DISPLAY INVISIBLE (-5500 8000);
FORCEPROP 1 LAST MATERIAL CHIP
J 0
(-5475 8125);
DISPLAY 0.617021 (-5475 8125);
PAINT SKYBLUE (-5475 8125);
FORCEPROP 1 LAST WATTAGE 1/16W
J 2
(-5125 8075);
DISPLAY 0.617021 (-5125 8075);
PAINT SKYBLUE (-5125 8075);
FORCEPROP 1 LAST PACK_TYPE 0402LF
J 0
(-5475 8075);
DISPLAY 0.617021 (-5475 8075);
PAINT SKYBLUE (-5475 8075);
FORCEPROP 1 LAST TOLERANCE 5%
J 0
(-5125 8175);
DISPLAY 0.617021 (-5125 8175);
PAINT SKYBLUE (-5125 8175);
FORCEPROP 1 LAST VALUE 0
J 2
(-5250 8225);
DISPLAY 0.617021 (-5250 8225);
PAINT SKYBLUE (-5250 8225);
FORCEPROP 1 LAST LOCATION PR1797
J 0
(-5500 8175);
DISPLAY 0.617021 (-5500 8175);
PAINT AQUA (-5500 8175);
FORCEPROP 1 LASTPIN (-5375 8175) $PN 1
J 0
(-5363 8187);
DISPLAY 0.617021 (-5363 8187);
FORCEPROP 1 LASTPIN (-5175 8175) $PN 2
J 0
(-5213 8187);
DISPLAY 0.617021 (-5213 8187);
FORCEPROP 2 LAST CDS_LIB pure_quanta
J 0
(-5275 8175);
PAINT MONO (-5275 8175);
DISPLAY INVISIBLE (-5275 8175);
FORCEPROP 1 LAST PATH I31
J 0
(-5325 8325);
DISPLAY 0.978723 (-5325 8325);
PAINT WHITE (-5325 8325);
DISPLAY INVISIBLE (-5325 8325);
FORCEPROP 2 LAST $SEC 1
J 0
(-5325 8375);
DISPLAY 0.680851 (-5325 8375);
PAINT MONO (-5325 8375);
DISPLAY INVISIBLE (-5325 8375);
FORCEPROP 2 LAST CDS_SEC 1
J 0
(-5325 8375);
DISPLAY 1.021277 (-5325 8375);
DISPLAY INVISIBLE (-5325 8375);
FORCEADD Q_CAP..1
(-3700 8225);
FORCEPROP 1 LAST PART_NUMBER CH622KMEA03
J 0
(-3650 8050);
DISPLAY 0.617021 (-3650 8050);
PAINT BLUE (-3650 8050);
DISPLAY INVISIBLE (-3650 8050);
FORCEPROP 1 LAST TOLERANCE 20%
J 0
(-3650 8200);
DISPLAY 0.617021 (-3650 8200);
PAINT SKYBLUE (-3650 8200);
FORCEPROP 1 LAST PACK_TYPE C0805
J 0
(-3650 8100);
DISPLAY 0.617021 (-3650 8100);
PAINT SKYBLUE (-3650 8100);
FORCEPROP 1 LAST MATERIAL X6S
J 0
(-3650 8150);
DISPLAY 0.617021 (-3650 8150);
PAINT SKYBLUE (-3650 8150);
FORCEPROP 1 LAST VALUE 22UF
J 0
(-3650 8300);
DISPLAY 0.617021 (-3650 8300);
PAINT SKYBLUE (-3650 8300);
FORCEPROP 1 LAST VOLTAGE 4V
J 0
(-3650 8250);
DISPLAY 0.617021 (-3650 8250);
PAINT SKYBLUE (-3650 8250);
FORCEPROP 1 LAST LOCATION PC456_P1_2
J 0
(-3650 8350);
DISPLAY 0.617021 (-3650 8350);
PAINT AQUA (-3650 8350);
FORCEPROP 1 LASTPIN (-3700 8325) $PN 1
J 0
(-3690 8305);
DISPLAY 0.617021 (-3690 8305);
PAINT MONO (-3690 8305);
FORCEPROP 1 LASTPIN (-3700 8125) $PN 2
J 0
(-3690 8105);
DISPLAY 0.617021 (-3690 8105);
PAINT MONO (-3690 8105);
FORCEPROP 2 LAST CDS_LIB pure_quanta
J 0
(-3700 8225);
DISPLAY INVISIBLE (-3700 8225);
FORCEPROP 1 LAST PATH I32
J 0
(-3650 8375);
DISPLAY 0.978723 (-3650 8375);
PAINT WHITE (-3650 8375);
DISPLAY INVISIBLE (-3650 8375);
FORCEPROP 1 LAST LOCATION PC456_P1_2
J 0
(-3650 8400);
DISPLAY 1.021277 (-3650 8400);
PAINT AQUA (-3650 8400);
DISPLAY INVISIBLE (-3650 8400);
FORCEPROP 0 LAST $SEC 1
J 0
(-3650 8400);
DISPLAY 0.680851 (-3650 8400);
PAINT MONO (-3650 8400);
DISPLAY INVISIBLE (-3650 8400);
FORCEPROP 0 LAST CDS_SEC 1
J 0
(-3650 8400);
DISPLAY 1.021277 (-3650 8400);
DISPLAY INVISIBLE (-3650 8400);
FORCEADD Q_CAP..1
(-3275 8225);
FORCEPROP 1 LAST PART_NUMBER CH622KMEA03
J 0
(-3225 8050);
DISPLAY 0.617021 (-3225 8050);
PAINT BLUE (-3225 8050);
DISPLAY INVISIBLE (-3225 8050);
FORCEPROP 1 LAST TOLERANCE 20%
J 0
(-3225 8200);
DISPLAY 0.617021 (-3225 8200);
PAINT SKYBLUE (-3225 8200);
FORCEPROP 1 LAST PACK_TYPE C0805
J 0
(-3225 8100);
DISPLAY 0.617021 (-3225 8100);
PAINT SKYBLUE (-3225 8100);
FORCEPROP 1 LAST MATERIAL X6S
J 0
(-3225 8150);
DISPLAY 0.617021 (-3225 8150);
PAINT SKYBLUE (-3225 8150);
FORCEPROP 1 LAST VOLTAGE 4V
J 0
(-3225 8250);
DISPLAY 0.617021 (-3225 8250);
PAINT SKYBLUE (-3225 8250);
FORCEPROP 1 LAST VALUE 22UF
J 0
(-3225 8300);
DISPLAY 0.617021 (-3225 8300);
PAINT SKYBLUE (-3225 8300);
FORCEPROP 1 LAST LOCATION PC458_P1_2
J 0
(-3225 8350);
DISPLAY 0.617021 (-3225 8350);
PAINT AQUA (-3225 8350);
FORCEPROP 1 LASTPIN (-3275 8325) $PN 1
J 0
(-3265 8305);
DISPLAY 0.617021 (-3265 8305);
PAINT MONO (-3265 8305);
FORCEPROP 1 LASTPIN (-3275 8125) $PN 2
J 0
(-3265 8105);
DISPLAY 0.617021 (-3265 8105);
PAINT MONO (-3265 8105);
FORCEPROP 2 LAST CDS_LIB pure_quanta
J 0
(-3275 8225);
DISPLAY INVISIBLE (-3275 8225);
FORCEPROP 1 LAST PATH I33
J 0
(-3225 8375);
DISPLAY 0.978723 (-3225 8375);
PAINT WHITE (-3225 8375);
DISPLAY INVISIBLE (-3225 8375);
FORCEPROP 1 LAST LOCATION PC458_P1_2
J 0
(-3225 8400);
DISPLAY 1.021277 (-3225 8400);
PAINT AQUA (-3225 8400);
DISPLAY INVISIBLE (-3225 8400);
FORCEPROP 0 LAST $SEC 1
J 0
(-3225 8400);
DISPLAY 0.680851 (-3225 8400);
PAINT MONO (-3225 8400);
DISPLAY INVISIBLE (-3225 8400);
FORCEPROP 0 LAST CDS_SEC 1
J 0
(-3225 8400);
DISPLAY 1.021277 (-3225 8400);
DISPLAY INVISIBLE (-3225 8400);
FORCEADD Q_RES..2
(-2800 8225);
FORCEPROP 1 LAST PART_NUMBER CS14992FB06
J 0
(-2760 8100);
DISPLAY 0.617021 (-2760 8100);
PAINT BLUE (-2760 8100);
DISPLAY INVISIBLE (-2760 8100);
FORCEPROP 1 LAST VALUE 499
J 0
(-2755 8300);
DISPLAY 0.617021 (-2755 8300);
PAINT SKYBLUE (-2755 8300);
FORCEPROP 1 LAST TOLERANCE 1%
J 0
(-2755 8250);
DISPLAY 0.617021 (-2755 8250);
PAINT SKYBLUE (-2755 8250);
FORCEPROP 1 LAST MATERIAL CHIP
J 0
(-2760 8150);
DISPLAY 0.617021 (-2760 8150);
PAINT SKYBLUE (-2760 8150);
FORCEPROP 1 LAST PACK_TYPE 0402LF
J 0
(-2760 8050);
DISPLAY 0.617021 (-2760 8050);
PAINT SKYBLUE (-2760 8050);
FORCEPROP 1 LAST WATTAGE 1/16W
J 0
(-2760 8200);
DISPLAY 0.617021 (-2760 8200);
PAINT SKYBLUE (-2760 8200);
FORCEPROP 1 LAST LOCATION PR4247
J 0
(-2755 8350);
DISPLAY 0.617021 (-2755 8350);
PAINT AQUA (-2755 8350);
FORCEPROP 1 LASTPIN (-2800 8325) $PN 1
J 0
(-2795 8287);
DISPLAY 0.787234 (-2795 8287);
PAINT MONO (-2795 8287);
FORCEPROP 1 LASTPIN (-2800 8125) $PN 2
J 0
(-2795 8135);
DISPLAY 0.787234 (-2795 8135);
PAINT MONO (-2795 8135);
FORCEPROP 2 LAST BOM_COST VR_PCH
J 0
(-2750 8400);
DISPLAY 0.680851 (-2750 8400);
DISPLAY INVISIBLE (-2750 8400);
FORCEPROP 2 LAST CDS_LIB pure_quanta
J 0
(-2800 8225);
DISPLAY INVISIBLE (-2800 8225);
FORCEPROP 1 LAST PATH I34
J 0
(-2750 8400);
DISPLAY 0.978723 (-2750 8400);
PAINT WHITE (-2750 8400);
DISPLAY INVISIBLE (-2750 8400);
FORCEPROP 0 LAST $SEC 1
J 0
(-2750 8400);
DISPLAY 0.680851 (-2750 8400);
PAINT MONO (-2750 8400);
DISPLAY INVISIBLE (-2750 8400);
FORCEPROP 0 LAST CDS_SEC 1
J 0
(-2750 8400);
DISPLAY 1.021277 (-2750 8400);
DISPLAY INVISIBLE (-2750 8400);
FORCEADD UNIVERSAL_GND..1
(-2425 7850);
FORCEPROP 3 LASTPIN (-2425 7900) SIG_NAME GND\g
J 0
(-2415 7910);
DISPLAY 0.659574 (-2415 7910);
PAINT MONO (-2415 7910);
DISPLAY INVISIBLE (-2415 7910);
FORCEPROP 1 LAST HDL_POWER GND
J 1
(-2400 7775);
DISPLAY 0.872340 (-2400 7775);
PAINT GREEN (-2400 7775);
DISPLAY INVISIBLE (-2400 7775);
FORCEPROP 2 LAST CDS_LIB logical_power
J 0
(-2425 7850);
PAINT MONO (-2425 7850);
DISPLAY INVISIBLE (-2425 7850);
FORCEPROP 1 LAST PATH I35
J 0
(-2350 7850);
DISPLAY 0.872340 (-2350 7850);
PAINT AQUA (-2350 7850);
DISPLAY INVISIBLE (-2350 7850);
FORCEADD Q_CAP..1
(-6175 9325);
FORCEPROP 1 LAST PART_NUMBER TMP_QCH2336K1B12
J 0
(-6125 9175);
DISPLAY 0.617021 (-6125 9175);
PAINT BLUE (-6125 9175);
DISPLAY INVISIBLE (-6125 9175);
FORCEPROP 1 LAST TOLERANCE 10%
J 0
(-6125 9325);
DISPLAY 0.617021 (-6125 9325);
PAINT SKYBLUE (-6125 9325);
FORCEPROP 1 LAST MATERIAL X7R
J 0
(-6125 9275);
DISPLAY 0.617021 (-6125 9275);
PAINT SKYBLUE (-6125 9275);
FORCEPROP 1 LAST PACK_TYPE 0402
J 0
(-6125 9225);
DISPLAY 0.617021 (-6125 9225);
PAINT SKYBLUE (-6125 9225);
FORCEPROP 1 LAST VALUE 3300PF
J 0
(-6125 9425);
DISPLAY 0.617021 (-6125 9425);
PAINT SKYBLUE (-6125 9425);
FORCEPROP 1 LAST VOLTAGE 50V
J 0
(-6125 9375);
DISPLAY 0.617021 (-6125 9375);
PAINT SKYBLUE (-6125 9375);
FORCEPROP 1 LAST LOCATION PC443_P1_2
J 0
(-6125 9475);
DISPLAY 0.617021 (-6125 9475);
PAINT AQUA (-6125 9475);
FORCEPROP 1 LASTPIN (-6175 9425) $PN 1
J 0
(-6165 9405);
DISPLAY 0.617021 (-6165 9405);
PAINT MONO (-6165 9405);
FORCEPROP 1 LASTPIN (-6175 9225) $PN 2
J 0
(-6165 9205);
DISPLAY 0.617021 (-6165 9205);
PAINT MONO (-6165 9205);
FORCEPROP 2 LAST CDS_LIB pure_quanta
J 0
(-6175 9325);
DISPLAY INVISIBLE (-6175 9325);
FORCEPROP 1 LAST PATH I36
J 0
(-6125 9475);
DISPLAY 0.978723 (-6125 9475);
PAINT WHITE (-6125 9475);
DISPLAY INVISIBLE (-6125 9475);
FORCEPROP 1 LAST LOCATION PC443_P1_2
J 0
(-6125 9525);
DISPLAY 1.021277 (-6125 9525);
PAINT AQUA (-6125 9525);
DISPLAY INVISIBLE (-6125 9525);
FORCEPROP 0 LAST $SEC 1
J 0
(-6125 9525);
DISPLAY 0.680851 (-6125 9525);
PAINT MONO (-6125 9525);
DISPLAY INVISIBLE (-6125 9525);
FORCEPROP 0 LAST CDS_SEC 1
J 0
(-6125 9525);
DISPLAY 1.021277 (-6125 9525);
DISPLAY INVISIBLE (-6125 9525);
FORCEADD Q_CAP..1
(-5775 9325);
FORCEPROP 1 LAST PART_NUMBER CH5103KEB01
J 0
(-5725 9175);
DISPLAY 0.617021 (-5725 9175);
PAINT BLUE (-5725 9175);
DISPLAY INVISIBLE (-5725 9175);
FORCEPROP 1 LAST PACK_TYPE C0402
J 0
(-5725 9225);
DISPLAY 0.617021 (-5725 9225);
PAINT SKYBLUE (-5725 9225);
FORCEPROP 1 LAST VALUE 1UF
J 0
(-5725 9425);
DISPLAY 0.617021 (-5725 9425);
PAINT SKYBLUE (-5725 9425);
FORCEPROP 1 LAST MATERIAL X6S
J 0
(-5725 9275);
DISPLAY 0.617021 (-5725 9275);
PAINT SKYBLUE (-5725 9275);
FORCEPROP 1 LAST TOLERANCE 10%
J 0
(-5725 9325);
DISPLAY 0.617021 (-5725 9325);
PAINT SKYBLUE (-5725 9325);
FORCEPROP 1 LAST VOLTAGE 16V
J 0
(-5725 9375);
DISPLAY 0.617021 (-5725 9375);
PAINT SKYBLUE (-5725 9375);
FORCEPROP 1 LAST LOCATION PC445_P1_2
J 0
(-5725 9475);
DISPLAY 0.617021 (-5725 9475);
PAINT AQUA (-5725 9475);
FORCEPROP 1 LASTPIN (-5775 9425) $PN 1
J 0
(-5765 9405);
DISPLAY 0.617021 (-5765 9405);
PAINT MONO (-5765 9405);
FORCEPROP 1 LASTPIN (-5775 9225) $PN 2
J 0
(-5765 9205);
DISPLAY 0.617021 (-5765 9205);
PAINT MONO (-5765 9205);
FORCEPROP 2 LAST CDS_LIB pure_quanta
J 0
(-5775 9325);
DISPLAY INVISIBLE (-5775 9325);
FORCEPROP 1 LAST PATH I37
J 0
(-5725 9475);
DISPLAY 0.978723 (-5725 9475);
PAINT WHITE (-5725 9475);
DISPLAY INVISIBLE (-5725 9475);
FORCEPROP 1 LAST LOCATION PC445_P1_2
J 0
(-5725 9525);
DISPLAY 1.021277 (-5725 9525);
PAINT AQUA (-5725 9525);
DISPLAY INVISIBLE (-5725 9525);
FORCEPROP 0 LAST $SEC 1
J 0
(-5725 9525);
DISPLAY 0.680851 (-5725 9525);
PAINT MONO (-5725 9525);
DISPLAY INVISIBLE (-5725 9525);
FORCEPROP 0 LAST CDS_SEC 1
J 0
(-5725 9525);
DISPLAY 1.021277 (-5725 9525);
DISPLAY INVISIBLE (-5725 9525);
FORCEADD ISL99390FRZTR5935..1
(-6975 11225);
FORCEPROP 1 LAST PART_NUMBER AL099390004
J 0
(-7275 12025);
DISPLAY 0.723404 (-7275 12025);
PAINT GREEN (-7275 12025);
DISPLAY INVISIBLE (-7275 12025);
FORCEPROP 2 LAST VALUE ISL99390FRZ-TR5935
J 0
(-7250 12250);
DISPLAY 0.617021 (-7250 12250);
PAINT SKYBLUE (-7250 12250);
FORCEPROP 2 LAST PART_TYPE SMLF
J 0
(-7250 12300);
DISPLAY 0.808511 (-7250 12300);
FORCEPROP 1 LAST MATERIAL IC
J 0
(-7275 11950);
DISPLAY 0.723404 (-7275 11950);
PAINT GREEN (-7275 11950);
FORCEPROP 1 LAST LOCATION PU50_P1_1
J 0
(-7275 12100);
DISPLAY 0.723404 (-7275 12100);
PAINT GREEN (-7275 12100);
FORCEPROP 2 LASTPIN (-6575 10775) $PN 2
J 0
(-6565 10785);
DISPLAY 0.680851 (-6565 10785);
PAINT MONO (-6565 10785);
FORCEPROP 2 LASTPIN (-6575 11575) $PN 33
J 0
(-6565 11585);
DISPLAY 0.680851 (-6565 11585);
PAINT MONO (-6565 11585);
FORCEPROP 2 LASTPIN (-7425 10975) $PN 31
J 2
(-7435 10985);
DISPLAY 0.680851 (-7435 10985);
PAINT MONO (-7435 10985);
FORCEPROP 2 LASTPIN (-7425 11375) $PN 35
J 2
(-7435 11385);
DISPLAY 0.680851 (-7435 11385);
PAINT MONO (-7435 11385);
FORCEPROP 2 LASTPIN (-6575 10925) $PN 6
J 0
(-6565 10935);
DISPLAY 0.680851 (-6565 10935);
PAINT MONO (-6565 10935);
FORCEPROP 2 LASTPIN (-6575 10875) $PN 41
J 0
(-6565 10885);
DISPLAY 0.680851 (-6565 10885);
PAINT MONO (-6565 10885);
FORCEPROP 2 LASTPIN (-7425 11225) $PN 38
J 2
(-7435 11235);
DISPLAY 0.680851 (-7435 11235);
PAINT MONO (-7435 11235);
FORCEPROP 2 LASTPIN (-7425 10925) $PN 37
J 2
(-7435 10935);
DISPLAY 0.680851 (-7435 10935);
PAINT MONO (-7435 10935);
FORCEPROP 2 LASTPIN (-6575 10725) $PN 5
J 0
(-6565 10735);
DISPLAY 0.680851 (-6565 10735);
PAINT MONO (-6565 10735);
FORCEPROP 2 LASTPIN (-6575 10675) $PN 7_9-20_24
J 0
(-6565 10685);
DISPLAY 0.680851 (-6565 10685);
PAINT MONO (-6565 10685);
FORCEPROP 2 LASTPIN (-6575 10625) $PN 40
J 0
(-6565 10635);
DISPLAY 0.680851 (-6565 10635);
PAINT MONO (-6565 10635);
FORCEPROP 2 LASTPIN (-6575 11325) $PN 32
J 0
(-6565 11335);
DISPLAY 0.680851 (-6565 11335);
PAINT MONO (-6565 11335);
FORCEPROP 2 LASTPIN (-7425 11875) $PN 4
J 2
(-7435 11885);
DISPLAY 0.680851 (-7435 11885);
PAINT MONO (-7435 11885);
FORCEPROP 2 LASTPIN (-7425 10625) $PN 34
J 2
(-7435 10635);
DISPLAY 0.680851 (-7435 10635);
PAINT MONO (-7435 10635);
FORCEPROP 2 LASTPIN (-7425 11125) $PN 39
J 2
(-7435 11135);
DISPLAY 0.680851 (-7435 11135);
PAINT MONO (-7435 11135);
FORCEPROP 2 LASTPIN (-6575 11225) $PN 10_19
J 0
(-6565 11235);
DISPLAY 0.680851 (-6565 11235);
PAINT MONO (-6565 11235);
FORCEPROP 2 LASTPIN (-7425 10725) $PN 36
J 2
(-7435 10735);
DISPLAY 0.680851 (-7435 10735);
PAINT MONO (-7435 10735);
FORCEPROP 2 LASTPIN (-7425 11575) $PN 3
J 2
(-7435 11585);
DISPLAY 0.680851 (-7435 11585);
PAINT MONO (-7435 11585);
FORCEPROP 2 LASTPIN (-6575 11875) $PN 25_29
J 0
(-6565 11885);
DISPLAY 0.680851 (-6565 11885);
PAINT MONO (-6565 11885);
FORCEPROP 2 LASTPIN (-6575 11825) $PN 30
J 0
(-6565 11835);
DISPLAY 0.680851 (-6565 11835);
PAINT MONO (-6565 11835);
FORCEPROP 2 LASTPIN (-6575 10975) $PN 1
J 0
(-6565 10985);
DISPLAY 0.680851 (-6565 10985);
PAINT MONO (-6565 10985);
FORCEPROP 2 LAST SEC_TYPE 
J 0
(-7250 12350);
DISPLAY 1.021277 (-7250 12350);
DISPLAY INVISIBLE (-7250 12350);
FORCEPROP 2 LAST CDS_LIB pure_quanta
J 0
(-6975 11225);
DISPLAY INVISIBLE (-6975 11225);
FORCEPROP 1 LAST CDS_LMAN_SYM_OUTLINE -300,700,250,-650
J 0
(-6975 11225);
DISPLAY 0.468085 (-6975 11225);
PAINT GREEN (-6975 11225);
DISPLAY INVISIBLE (-6975 11225);
FORCEPROP 1 LAST NEEDS_NO_SIZE TRUE
J 0
(-6975 11225);
DISPLAY 0.723404 (-6975 11225);
PAINT GREEN (-6975 11225);
DISPLAY INVISIBLE (-6975 11225);
FORCEPROP 1 LAST PATH I38
J 0
(-6975 11225);
DISPLAY 0.723404 (-6975 11225);
PAINT GREEN (-6975 11225);
DISPLAY INVISIBLE (-6975 11225);
FORCEPROP 2 LAST SEC 1
J 0
(-7250 12350);
DISPLAY 0.680851 (-7250 12350);
PAINT MONO (-7250 12350);
DISPLAY INVISIBLE (-7250 12350);
FORCEADD UNIVERSAL_GND..1
(-6325 10500);
FORCEPROP 3 LASTPIN (-6325 10550) SIG_NAME GND\g
J 0
(-6315 10560);
DISPLAY 0.659574 (-6315 10560);
PAINT MONO (-6315 10560);
DISPLAY INVISIBLE (-6315 10560);
FORCEPROP 1 LAST HDL_POWER GND
J 1
(-6300 10425);
DISPLAY 0.872340 (-6300 10425);
PAINT GREEN (-6300 10425);
DISPLAY INVISIBLE (-6300 10425);
FORCEPROP 2 LAST CDS_LIB logical_power
J 0
(-6325 10500);
PAINT MONO (-6325 10500);
DISPLAY INVISIBLE (-6325 10500);
FORCEPROP 1 LAST PATH I39
J 0
(-6250 10500);
DISPLAY 0.872340 (-6250 10500);
PAINT AQUA (-6250 10500);
DISPLAY INVISIBLE (-6250 10500);
FORCEADD OFFPAGE..1
(-8425 7825);
FORCEPROP 2 LAST $XR0 292 
J 0
(-8677 7825);
DISPLAY 0.638298 (-8677 7825);
PAINT MONO (-8677 7825);
FORCEPROP 1 LAST COMMENT_BODY TRUE
J 0
(-8300 7725);
DISPLAY 0.872340 (-8300 7725);
PAINT GREEN (-8300 7725);
DISPLAY INVISIBLE (-8300 7725);
FORCEPROP 1 LAST OFFPAGE TRUE
J 0
(-8100 7700);
DISPLAY 0.872340 (-8100 7700);
PAINT GREEN (-8100 7700);
DISPLAY INVISIBLE (-8100 7700);
FORCEPROP 2 LAST CDS_LIB standard
J 0
(-8425 7825);
DISPLAY INVISIBLE (-8425 7825);
FORCEPROP 2 LAST PATH I4
J 0
(-8675 7875);
DISPLAY 1.021277 (-8675 7875);
DISPLAY INVISIBLE (-8675 7875);
FORCEADD Q_CAP..1
(-6175 12125);
FORCEPROP 1 LAST PART_NUMBER TMP_QCH2336K1B12
J 0
(-6125 11975);
DISPLAY 0.617021 (-6125 11975);
PAINT BLUE (-6125 11975);
DISPLAY INVISIBLE (-6125 11975);
FORCEPROP 1 LAST PACK_TYPE 0402
J 0
(-6125 12025);
DISPLAY 0.617021 (-6125 12025);
PAINT SKYBLUE (-6125 12025);
FORCEPROP 1 LAST VOLTAGE 50V
J 0
(-6125 12175);
DISPLAY 0.617021 (-6125 12175);
PAINT SKYBLUE (-6125 12175);
FORCEPROP 1 LAST VALUE 3300PF
J 0
(-6125 12225);
DISPLAY 0.617021 (-6125 12225);
PAINT SKYBLUE (-6125 12225);
FORCEPROP 1 LAST TOLERANCE 10%
J 0
(-6125 12125);
DISPLAY 0.617021 (-6125 12125);
PAINT SKYBLUE (-6125 12125);
FORCEPROP 1 LAST MATERIAL X7R
J 0
(-6125 12075);
DISPLAY 0.617021 (-6125 12075);
PAINT SKYBLUE (-6125 12075);
FORCEPROP 1 LAST LOCATION PC442_P1_1
J 0
(-6125 12275);
DISPLAY 0.617021 (-6125 12275);
PAINT AQUA (-6125 12275);
FORCEPROP 1 LASTPIN (-6175 12225) $PN 1
J 0
(-6165 12205);
DISPLAY 0.617021 (-6165 12205);
PAINT MONO (-6165 12205);
FORCEPROP 1 LASTPIN (-6175 12025) $PN 2
J 0
(-6165 12005);
DISPLAY 0.617021 (-6165 12005);
PAINT MONO (-6165 12005);
FORCEPROP 2 LAST CDS_LIB pure_quanta
J 0
(-6175 12125);
DISPLAY INVISIBLE (-6175 12125);
FORCEPROP 1 LAST PATH I40
J 0
(-6125 12275);
DISPLAY 0.978723 (-6125 12275);
PAINT WHITE (-6125 12275);
DISPLAY INVISIBLE (-6125 12275);
FORCEPROP 1 LAST LOCATION PC442_P1_1
J 0
(-6125 12325);
DISPLAY 1.021277 (-6125 12325);
PAINT AQUA (-6125 12325);
DISPLAY INVISIBLE (-6125 12325);
FORCEPROP 0 LAST $SEC 1
J 0
(-6125 12325);
DISPLAY 0.680851 (-6125 12325);
PAINT MONO (-6125 12325);
DISPLAY INVISIBLE (-6125 12325);
FORCEPROP 0 LAST CDS_SEC 1
J 0
(-6125 12325);
DISPLAY 1.021277 (-6125 12325);
DISPLAY INVISIBLE (-6125 12325);
FORCEADD Q_CAP..1
(-5775 12125);
FORCEPROP 1 LAST PART_NUMBER CH5103KEB01
J 0
(-5725 11975);
DISPLAY 0.617021 (-5725 11975);
PAINT BLUE (-5725 11975);
DISPLAY INVISIBLE (-5725 11975);
FORCEPROP 1 LAST PACK_TYPE C0402
J 0
(-5725 12025);
DISPLAY 0.617021 (-5725 12025);
PAINT SKYBLUE (-5725 12025);
FORCEPROP 1 LAST VOLTAGE 16V
J 0
(-5725 12175);
DISPLAY 0.617021 (-5725 12175);
PAINT SKYBLUE (-5725 12175);
FORCEPROP 1 LAST VALUE 1UF
J 0
(-5725 12225);
DISPLAY 0.617021 (-5725 12225);
PAINT SKYBLUE (-5725 12225);
FORCEPROP 1 LAST TOLERANCE 10%
J 0
(-5725 12125);
DISPLAY 0.617021 (-5725 12125);
PAINT SKYBLUE (-5725 12125);
FORCEPROP 1 LAST MATERIAL X6S
J 0
(-5725 12075);
DISPLAY 0.617021 (-5725 12075);
PAINT SKYBLUE (-5725 12075);
FORCEPROP 1 LAST LOCATION PC444_P1_1
J 0
(-5725 12275);
DISPLAY 0.617021 (-5725 12275);
PAINT AQUA (-5725 12275);
FORCEPROP 1 LASTPIN (-5775 12225) $PN 1
J 0
(-5765 12205);
DISPLAY 0.617021 (-5765 12205);
PAINT MONO (-5765 12205);
FORCEPROP 1 LASTPIN (-5775 12025) $PN 2
J 0
(-5765 12005);
DISPLAY 0.617021 (-5765 12005);
PAINT MONO (-5765 12005);
FORCEPROP 2 LAST CDS_LIB pure_quanta
J 0
(-5775 12125);
DISPLAY INVISIBLE (-5775 12125);
FORCEPROP 1 LAST PATH I41
J 0
(-5725 12275);
DISPLAY 0.978723 (-5725 12275);
PAINT WHITE (-5725 12275);
DISPLAY INVISIBLE (-5725 12275);
FORCEPROP 1 LAST LOCATION PC444_P1_1
J 0
(-5725 12325);
DISPLAY 1.021277 (-5725 12325);
PAINT AQUA (-5725 12325);
DISPLAY INVISIBLE (-5725 12325);
FORCEPROP 0 LAST $SEC 1
J 0
(-5725 12325);
DISPLAY 0.680851 (-5725 12325);
PAINT MONO (-5725 12325);
DISPLAY INVISIBLE (-5725 12325);
FORCEPROP 0 LAST CDS_SEC 1
J 0
(-5725 12325);
DISPLAY 1.021277 (-5725 12325);
DISPLAY INVISIBLE (-5725 12325);
FORCEADD Q_RES..1
(-5625 8875);
FORCEPROP 1 LAST PART_NUMBER CS-3302FB01
J 0
(-5850 8725);
DISPLAY 0.617021 (-5850 8725);
PAINT BLUE (-5850 8725);
DISPLAY INVISIBLE (-5850 8725);
FORCEPROP 1 LAST PACK_TYPE 0402LF
J 0
(-5850 8825);
DISPLAY 0.617021 (-5850 8825);
PAINT SKYBLUE (-5850 8825);
FORCEPROP 1 LAST MATERIAL CHIP
J 0
(-5650 8775);
DISPLAY 0.617021 (-5650 8775);
PAINT SKYBLUE (-5650 8775);
FORCEPROP 1 LAST WATTAGE 1/16W
J 2
(-5700 8775);
DISPLAY 0.617021 (-5700 8775);
PAINT SKYBLUE (-5700 8775);
FORCEPROP 1 LAST TOLERANCE 1%
J 0
(-5425 8875);
DISPLAY 0.617021 (-5425 8875);
PAINT SKYBLUE (-5425 8875);
FORCEPROP 1 LAST VALUE 3.3
J 2
(-5450 8875);
DISPLAY 0.617021 (-5450 8875);
PAINT SKYBLUE (-5450 8875);
FORCEPROP 1 LAST LOCATION PR1795
J 0
(-5850 8875);
DISPLAY 0.617021 (-5850 8875);
PAINT AQUA (-5850 8875);
FORCEPROP 1 LASTPIN (-5725 8875) $PN 1
J 0
(-5713 8887);
DISPLAY 0.617021 (-5713 8887);
FORCEPROP 1 LASTPIN (-5525 8875) $PN 2
J 0
(-5563 8887);
DISPLAY 0.617021 (-5563 8887);
FORCEPROP 2 LAST CDS_LIB pure_quanta
J 0
(-5625 8875);
PAINT MONO (-5625 8875);
DISPLAY INVISIBLE (-5625 8875);
FORCEPROP 1 LAST PATH I42
J 0
(-5675 9025);
DISPLAY 0.978723 (-5675 9025);
PAINT WHITE (-5675 9025);
DISPLAY INVISIBLE (-5675 9025);
FORCEPROP 2 LAST $SEC 1
J 0
(-5675 9075);
DISPLAY 0.680851 (-5675 9075);
PAINT MONO (-5675 9075);
DISPLAY INVISIBLE (-5675 9075);
FORCEPROP 2 LAST CDS_SEC 1
J 0
(-5675 9075);
DISPLAY 1.021277 (-5675 9075);
DISPLAY INVISIBLE (-5675 9075);
FORCEADD Q_CAP..1
(-5375 9325);
FORCEPROP 1 LAST PART_NUMBER CH6223MEA01
J 0
(-5325 9175);
DISPLAY 0.617021 (-5325 9175);
PAINT BLUE (-5325 9175);
DISPLAY INVISIBLE (-5325 9175);
FORCEPROP 1 LAST TOLERANCE 20%
J 0
(-5325 9325);
DISPLAY 0.617021 (-5325 9325);
PAINT SKYBLUE (-5325 9325);
FORCEPROP 1 LAST PACK_TYPE C0805
J 0
(-5325 9225);
DISPLAY 0.617021 (-5325 9225);
PAINT SKYBLUE (-5325 9225);
FORCEPROP 1 LAST VALUE 22UF
J 0
(-5325 9425);
DISPLAY 0.617021 (-5325 9425);
PAINT SKYBLUE (-5325 9425);
FORCEPROP 1 LAST VOLTAGE 16V
J 0
(-5325 9375);
DISPLAY 0.617021 (-5325 9375);
PAINT SKYBLUE (-5325 9375);
FORCEPROP 1 LAST MATERIAL X6S
J 0
(-5325 9275);
DISPLAY 0.617021 (-5325 9275);
PAINT SKYBLUE (-5325 9275);
FORCEPROP 1 LAST LOCATION PC449_P1_2
J 0
(-5325 9475);
DISPLAY 0.617021 (-5325 9475);
PAINT AQUA (-5325 9475);
FORCEPROP 1 LASTPIN (-5375 9425) $PN 1
J 0
(-5365 9405);
DISPLAY 0.617021 (-5365 9405);
PAINT MONO (-5365 9405);
FORCEPROP 1 LASTPIN (-5375 9225) $PN 2
J 0
(-5365 9205);
DISPLAY 0.617021 (-5365 9205);
PAINT MONO (-5365 9205);
FORCEPROP 2 LAST CDS_LIB pure_quanta
J 0
(-5375 9325);
DISPLAY INVISIBLE (-5375 9325);
FORCEPROP 1 LAST PATH I43
J 0
(-5325 9475);
DISPLAY 0.978723 (-5325 9475);
PAINT WHITE (-5325 9475);
DISPLAY INVISIBLE (-5325 9475);
FORCEPROP 1 LAST LOCATION PC449_P1_2
J 0
(-5325 9525);
DISPLAY 1.021277 (-5325 9525);
PAINT AQUA (-5325 9525);
DISPLAY INVISIBLE (-5325 9525);
FORCEPROP 0 LAST $SEC 1
J 0
(-5325 9525);
DISPLAY 0.680851 (-5325 9525);
PAINT MONO (-5325 9525);
DISPLAY INVISIBLE (-5325 9525);
FORCEPROP 0 LAST CDS_SEC 1
J 0
(-5325 9525);
DISPLAY 1.021277 (-5325 9525);
DISPLAY INVISIBLE (-5325 9525);
FORCEADD Q_CAP..1
R 2
(-4800 8700);
FORCEPROP 1 LAST PART_NUMBER CH4106K1B01
J 2
(-4850 8650);
DISPLAY 0.617021 (-4850 8650);
PAINT BLUE (-4850 8650);
DISPLAY INVISIBLE (-4850 8650);
FORCEPROP 1 LAST PACK_TYPE C0402
J 2
(-4850 8625);
DISPLAY 0.617021 (-4850 8625);
PAINT SKYBLUE (-4850 8625);
FORCEPROP 1 LAST VOLTAGE 50V
J 2
(-4850 8725);
DISPLAY 0.617021 (-4850 8725);
PAINT SKYBLUE (-4850 8725);
FORCEPROP 1 LAST VALUE 100NF
J 2
(-4850 8750);
DISPLAY 0.617021 (-4850 8750);
PAINT SKYBLUE (-4850 8750);
FORCEPROP 1 LAST TOLERANCE 10%
J 2
(-4850 8700);
DISPLAY 0.617021 (-4850 8700);
PAINT SKYBLUE (-4850 8700);
FORCEPROP 1 LAST MATERIAL X7R
J 2
(-4850 8675);
DISPLAY 0.617021 (-4850 8675);
PAINT SKYBLUE (-4850 8675);
FORCEPROP 1 LAST LOCATION PC447
J 2
(-4850 8775);
DISPLAY 0.617021 (-4850 8775);
PAINT AQUA (-4850 8775);
FORCEPROP 1 LASTPIN (-4800 8800) $PN 1
J 2
(-4810 8780);
DISPLAY 0.617021 (-4810 8780);
FORCEPROP 1 LASTPIN (-4800 8600) $PN 2
J 2
(-4810 8580);
DISPLAY 0.617021 (-4810 8580);
FORCEPROP 2 LAST CDS_LIB pure_quanta
J 2
(-4800 8700);
PAINT MONO (-4800 8700);
DISPLAY INVISIBLE (-4800 8700);
FORCEPROP 1 LAST PATH I44
J 2
(-4850 8850);
DISPLAY 0.978723 (-4850 8850);
PAINT WHITE (-4850 8850);
DISPLAY INVISIBLE (-4850 8850);
FORCEPROP 2 LAST $SEC 1
J 0
(-4850 8900);
DISPLAY 0.680851 (-4850 8900);
PAINT MONO (-4850 8900);
DISPLAY INVISIBLE (-4850 8900);
FORCEPROP 2 LAST CDS_SEC 1
J 0
(-4850 8900);
DISPLAY 1.021277 (-4850 8900);
DISPLAY INVISIBLE (-4850 8900);
FORCEADD Q_CAP..1
(-4975 9325);
FORCEPROP 1 LAST PART_NUMBER CH6223MEA01
J 0
(-4925 9175);
DISPLAY 0.617021 (-4925 9175);
PAINT BLUE (-4925 9175);
DISPLAY INVISIBLE (-4925 9175);
FORCEPROP 1 LAST TOLERANCE 20%
J 0
(-4925 9325);
DISPLAY 0.617021 (-4925 9325);
PAINT SKYBLUE (-4925 9325);
FORCEPROP 1 LAST VALUE 22UF
J 0
(-4925 9425);
DISPLAY 0.617021 (-4925 9425);
PAINT SKYBLUE (-4925 9425);
FORCEPROP 1 LAST PACK_TYPE C0805
J 0
(-4925 9225);
DISPLAY 0.617021 (-4925 9225);
PAINT SKYBLUE (-4925 9225);
FORCEPROP 1 LAST MATERIAL X6S
J 0
(-4925 9275);
DISPLAY 0.617021 (-4925 9275);
PAINT SKYBLUE (-4925 9275);
FORCEPROP 1 LAST VOLTAGE 16V
J 0
(-4925 9375);
DISPLAY 0.617021 (-4925 9375);
PAINT SKYBLUE (-4925 9375);
FORCEPROP 1 LAST LOCATION PC451_P1_2
J 0
(-4925 9475);
DISPLAY 0.617021 (-4925 9475);
PAINT AQUA (-4925 9475);
FORCEPROP 1 LASTPIN (-4975 9425) $PN 1
J 0
(-4965 9405);
DISPLAY 0.617021 (-4965 9405);
PAINT MONO (-4965 9405);
FORCEPROP 1 LASTPIN (-4975 9225) $PN 2
J 0
(-4965 9205);
DISPLAY 0.617021 (-4965 9205);
PAINT MONO (-4965 9205);
FORCEPROP 2 LAST CDS_LIB pure_quanta
J 0
(-4975 9325);
DISPLAY INVISIBLE (-4975 9325);
FORCEPROP 1 LAST PATH I45
J 0
(-4925 9475);
DISPLAY 0.978723 (-4925 9475);
PAINT WHITE (-4925 9475);
DISPLAY INVISIBLE (-4925 9475);
FORCEPROP 1 LAST LOCATION PC451_P1_2
J 0
(-4925 9525);
DISPLAY 1.021277 (-4925 9525);
PAINT AQUA (-4925 9525);
DISPLAY INVISIBLE (-4925 9525);
FORCEPROP 0 LAST $SEC 1
J 0
(-4925 9525);
DISPLAY 0.680851 (-4925 9525);
PAINT MONO (-4925 9525);
DISPLAY INVISIBLE (-4925 9525);
FORCEPROP 0 LAST CDS_SEC 1
J 0
(-4925 9525);
DISPLAY 1.021277 (-4925 9525);
DISPLAY INVISIBLE (-4925 9525);
FORCEADD Q_INDUCTOR..1
(-4575 8450);
FORCEPROP 1 LAST PART_NUMBER CV+12^0EZ03
J 0
(-4700 8560);
DISPLAY 0.617021 (-4700 8560);
PAINT BLUE (-4700 8560);
DISPLAY INVISIBLE (-4700 8560);
FORCEPROP 1 LAST MATERIAL IND
J 0
(-4700 8505);
DISPLAY 0.617021 (-4700 8505);
PAINT SKYBLUE (-4700 8505);
FORCEPROP 2 LAST VALUE 120NH/69A
J 0
(-4700 8700);
DISPLAY 0.617021 (-4700 8700);
PAINT SKYBLUE (-4700 8700);
FORCEPROP 2 LAST PACK_TYPE SMLF
J 0
(-4700 8650);
DISPLAY 0.617021 (-4700 8650);
PAINT SKYBLUE (-4700 8650);
FORCEPROP 1 LAST LOCATION PL22
J 0
(-4700 8610);
DISPLAY 0.617021 (-4700 8610);
PAINT AQUA (-4700 8610);
FORCEPROP 0 LASTPIN (-4675 8425) $PN 1
J 2
(-4685 8435);
DISPLAY 0.617021 (-4685 8435);
PAINT MONO (-4685 8435);
FORCEPROP 0 LASTPIN (-4475 8425) $PN 2
J 0
(-4465 8435);
DISPLAY 0.617021 (-4465 8435);
PAINT MONO (-4465 8435);
FORCEPROP 1 LAST NEEDS_NO_SIZE TRUE
J 0
(-4575 8450);
DISPLAY 0.468085 (-4575 8450);
PAINT GREEN (-4575 8450);
DISPLAY INVISIBLE (-4575 8450);
FORCEPROP 2 LAST CDS_LIB pure_quanta
J 0
(-4575 8450);
DISPLAY INVISIBLE (-4575 8450);
FORCEPROP 1 LAST PATH I46
J 0
(-4500 8505);
DISPLAY 0.723404 (-4500 8505);
PAINT GREEN (-4500 8505);
DISPLAY INVISIBLE (-4500 8505);
FORCEPROP 0 LAST $SEC 1
J 0
(-4700 8750);
DISPLAY 0.680851 (-4700 8750);
PAINT MONO (-4700 8750);
DISPLAY INVISIBLE (-4700 8750);
FORCEPROP 0 LAST CDS_SEC 1
J 0
(-4700 8750);
DISPLAY 1.021277 (-4700 8750);
DISPLAY INVISIBLE (-4700 8750);
FORCEADD UNIVERSAL_GND..1
(-4375 8900);
FORCEPROP 3 LASTPIN (-4375 8950) SIG_NAME GND\g
J 0
(-4365 8960);
DISPLAY 0.659574 (-4365 8960);
PAINT MONO (-4365 8960);
DISPLAY INVISIBLE (-4365 8960);
FORCEPROP 1 LAST HDL_POWER GND
J 1
(-4350 8825);
DISPLAY 0.872340 (-4350 8825);
PAINT GREEN (-4350 8825);
DISPLAY INVISIBLE (-4350 8825);
FORCEPROP 2 LAST CDS_LIB logical_power
J 0
(-4375 8900);
PAINT MONO (-4375 8900);
DISPLAY INVISIBLE (-4375 8900);
FORCEPROP 1 LAST PATH I47
J 0
(-4300 8900);
DISPLAY 0.872340 (-4300 8900);
PAINT AQUA (-4300 8900);
DISPLAY INVISIBLE (-4300 8900);
FORCEADD VCC15..1
(-4375 9700);
FORCEPROP 3 LASTPIN (-4375 9650) SIG_NAME SW_P12V_PVCCINFAON_CPU1_FLT\g
J 0
(-4365 9660);
DISPLAY 0.659574 (-4365 9660);
PAINT MONO (-4365 9660);
DISPLAY INVISIBLE (-4365 9660);
FORCEPROP 1 LAST HDL_POWER SW_P12V_PVCCINFAON_CPU1_FLT
J 1
(-4325 9750);
DISPLAY 0.617021 (-4325 9750);
PAINT GREEN (-4325 9750);
FORCEPROP 2 LAST CDS_LIB logical_power
J 0
(-4375 9700);
DISPLAY INVISIBLE (-4375 9700);
FORCEPROP 1 LAST PATH I48
J 0
(-4325 9725);
DISPLAY 0.872340 (-4325 9725);
PAINT AQUA (-4325 9725);
DISPLAY INVISIBLE (-4325 9725);
FORCEADD Q_RES..1
(-5250 10975);
FORCEPROP 1 LAST PART_NUMBER CS00002JB13
J 0
(-5375 10750);
DISPLAY 0.617021 (-5375 10750);
PAINT BLUE (-5375 10750);
DISPLAY INVISIBLE (-5375 10750);
FORCEPROP 1 LAST TOLERANCE 5%
J 0
(-5100 10975);
DISPLAY 0.617021 (-5100 10975);
PAINT SKYBLUE (-5100 10975);
FORCEPROP 1 LAST VALUE 0
J 2
(-5250 11025);
DISPLAY 0.617021 (-5250 11025);
PAINT SKYBLUE (-5250 11025);
FORCEPROP 1 LAST MATERIAL CHIP
J 0
(-5375 10900);
DISPLAY 0.617021 (-5375 10900);
PAINT SKYBLUE (-5375 10900);
FORCEPROP 1 LAST WATTAGE 1/16W
J 2
(-5225 10850);
DISPLAY 0.617021 (-5225 10850);
PAINT SKYBLUE (-5225 10850);
FORCEPROP 1 LAST PACK_TYPE 0402LF
J 0
(-5375 10800);
DISPLAY 0.617021 (-5375 10800);
PAINT SKYBLUE (-5375 10800);
FORCEPROP 1 LAST LOCATION PR1796
J 0
(-5475 10975);
DISPLAY 0.617021 (-5475 10975);
PAINT AQUA (-5475 10975);
FORCEPROP 1 LASTPIN (-5350 10975) $PN 1
J 0
(-5338 10987);
DISPLAY 0.617021 (-5338 10987);
FORCEPROP 1 LASTPIN (-5150 10975) $PN 2
J 0
(-5188 10987);
DISPLAY 0.617021 (-5188 10987);
FORCEPROP 2 LAST CDS_LIB pure_quanta
J 0
(-5250 10975);
PAINT MONO (-5250 10975);
DISPLAY INVISIBLE (-5250 10975);
FORCEPROP 1 LAST PATH I49
J 0
(-5300 11125);
DISPLAY 0.978723 (-5300 11125);
PAINT WHITE (-5300 11125);
DISPLAY INVISIBLE (-5300 11125);
FORCEPROP 2 LAST $SEC 1
J 0
(-5300 11175);
DISPLAY 0.680851 (-5300 11175);
PAINT MONO (-5300 11175);
DISPLAY INVISIBLE (-5300 11175);
FORCEPROP 2 LAST CDS_SEC 1
J 0
(-5300 11175);
DISPLAY 1.021277 (-5300 11175);
DISPLAY INVISIBLE (-5300 11175);
FORCEADD OFFPAGE..5
(-8425 7925);
FORCEPROP 2 LAST $XR1 292 
J 0
(-8830 7925);
DISPLAY 0.638298 (-8830 7925);
PAINT MONO (-8830 7925);
FORCEPROP 2 LAST $XR0 293 
J 0
(-8710 7925);
DISPLAY 0.638298 (-8710 7925);
PAINT MONO (-8710 7925);
FORCEPROP 1 LAST COMMENT_BODY TRUE
J 0
(-8325 7850);
DISPLAY 0.872340 (-8325 7850);
PAINT GREEN (-8325 7850);
DISPLAY INVISIBLE (-8325 7850);
FORCEPROP 1 LAST OFFPAGE TRUE
J 0
(-8100 7800);
DISPLAY 0.872340 (-8100 7800);
PAINT GREEN (-8100 7800);
DISPLAY INVISIBLE (-8100 7800);
FORCEPROP 2 LAST CDS_LIB standard
J 0
(-8425 7925);
DISPLAY INVISIBLE (-8425 7925);
FORCEPROP 2 LAST PATH I5
J 0
(-8700 7975);
DISPLAY 1.021277 (-8700 7975);
DISPLAY INVISIBLE (-8700 7975);
FORCEADD Q_RES..1
(-5625 11675);
FORCEPROP 1 LAST PART_NUMBER CS-3302FB01
J 0
(-5650 11625);
DISPLAY 0.617021 (-5650 11625);
PAINT BLUE (-5650 11625);
DISPLAY INVISIBLE (-5650 11625);
FORCEPROP 1 LAST VALUE 3.3
J 2
(-5450 11675);
DISPLAY 0.617021 (-5450 11675);
PAINT SKYBLUE (-5450 11675);
FORCEPROP 1 LAST WATTAGE 1/16W
J 2
(-5500 11575);
DISPLAY 0.617021 (-5500 11575);
PAINT SKYBLUE (-5500 11575);
FORCEPROP 1 LAST TOLERANCE 1%
J 0
(-5425 11675);
DISPLAY 0.617021 (-5425 11675);
PAINT SKYBLUE (-5425 11675);
FORCEPROP 1 LAST PACK_TYPE 0402LF
J 0
(-5850 11625);
DISPLAY 0.617021 (-5850 11625);
PAINT SKYBLUE (-5850 11625);
FORCEPROP 1 LAST MATERIAL CHIP
J 0
(-5850 11575);
DISPLAY 0.617021 (-5850 11575);
PAINT SKYBLUE (-5850 11575);
FORCEPROP 1 LAST LOCATION PR1794
J 0
(-5850 11675);
DISPLAY 0.617021 (-5850 11675);
PAINT AQUA (-5850 11675);
FORCEPROP 1 LASTPIN (-5725 11675) $PN 1
J 0
(-5713 11687);
DISPLAY 0.617021 (-5713 11687);
FORCEPROP 1 LASTPIN (-5525 11675) $PN 2
J 0
(-5563 11687);
DISPLAY 0.617021 (-5563 11687);
FORCEPROP 2 LAST CDS_LIB pure_quanta
J 0
(-5625 11675);
PAINT MONO (-5625 11675);
DISPLAY INVISIBLE (-5625 11675);
FORCEPROP 1 LAST PATH I50
J 0
(-5675 11825);
DISPLAY 0.978723 (-5675 11825);
PAINT WHITE (-5675 11825);
DISPLAY INVISIBLE (-5675 11825);
FORCEPROP 2 LAST $SEC 1
J 0
(-5675 11875);
DISPLAY 0.680851 (-5675 11875);
PAINT MONO (-5675 11875);
DISPLAY INVISIBLE (-5675 11875);
FORCEPROP 2 LAST CDS_SEC 1
J 0
(-5675 11875);
DISPLAY 1.021277 (-5675 11875);
DISPLAY INVISIBLE (-5675 11875);
FORCEADD Q_CAP..1
(-5375 12125);
FORCEPROP 1 LAST PART_NUMBER CH6223MEA01
J 0
(-5325 11975);
DISPLAY 0.617021 (-5325 11975);
PAINT BLUE (-5325 11975);
DISPLAY INVISIBLE (-5325 11975);
FORCEPROP 1 LAST TOLERANCE 20%
J 0
(-5325 12125);
DISPLAY 0.617021 (-5325 12125);
PAINT SKYBLUE (-5325 12125);
FORCEPROP 1 LAST PACK_TYPE C0805
J 0
(-5325 12025);
DISPLAY 0.617021 (-5325 12025);
PAINT SKYBLUE (-5325 12025);
FORCEPROP 1 LAST VOLTAGE 16V
J 0
(-5325 12175);
DISPLAY 0.617021 (-5325 12175);
PAINT SKYBLUE (-5325 12175);
FORCEPROP 1 LAST VALUE 22UF
J 0
(-5325 12225);
DISPLAY 0.617021 (-5325 12225);
PAINT SKYBLUE (-5325 12225);
FORCEPROP 1 LAST MATERIAL X6S
J 0
(-5325 12075);
DISPLAY 0.617021 (-5325 12075);
PAINT SKYBLUE (-5325 12075);
FORCEPROP 1 LAST LOCATION PC448_P1_1
J 0
(-5325 12275);
DISPLAY 0.617021 (-5325 12275);
PAINT AQUA (-5325 12275);
FORCEPROP 1 LASTPIN (-5375 12225) $PN 1
J 0
(-5365 12205);
DISPLAY 0.617021 (-5365 12205);
PAINT MONO (-5365 12205);
FORCEPROP 1 LASTPIN (-5375 12025) $PN 2
J 0
(-5365 12005);
DISPLAY 0.617021 (-5365 12005);
PAINT MONO (-5365 12005);
FORCEPROP 2 LAST CDS_LIB pure_quanta
J 0
(-5375 12125);
DISPLAY INVISIBLE (-5375 12125);
FORCEPROP 1 LAST PATH I51
J 0
(-5325 12275);
DISPLAY 0.978723 (-5325 12275);
PAINT WHITE (-5325 12275);
DISPLAY INVISIBLE (-5325 12275);
FORCEPROP 1 LAST LOCATION PC448_P1_1
J 0
(-5325 12325);
DISPLAY 1.021277 (-5325 12325);
PAINT AQUA (-5325 12325);
DISPLAY INVISIBLE (-5325 12325);
FORCEPROP 0 LAST $SEC 1
J 0
(-5325 12325);
DISPLAY 0.680851 (-5325 12325);
PAINT MONO (-5325 12325);
DISPLAY INVISIBLE (-5325 12325);
FORCEPROP 0 LAST CDS_SEC 1
J 0
(-5325 12325);
DISPLAY 1.021277 (-5325 12325);
DISPLAY INVISIBLE (-5325 12325);
FORCEADD Q_CAP..1
R 2
(-4800 11500);
FORCEPROP 1 LAST PART_NUMBER CH4106K1B01
J 2
(-4850 11450);
DISPLAY 0.617021 (-4850 11450);
PAINT BLUE (-4850 11450);
DISPLAY INVISIBLE (-4850 11450);
FORCEPROP 1 LAST VOLTAGE 50V
J 2
(-4850 11525);
DISPLAY 0.617021 (-4850 11525);
PAINT SKYBLUE (-4850 11525);
FORCEPROP 1 LAST PACK_TYPE C0402
J 2
(-4850 11425);
DISPLAY 0.617021 (-4850 11425);
PAINT SKYBLUE (-4850 11425);
FORCEPROP 1 LAST VALUE 100NF
J 2
(-4850 11550);
DISPLAY 0.617021 (-4850 11550);
PAINT SKYBLUE (-4850 11550);
FORCEPROP 1 LAST TOLERANCE 10%
J 2
(-4850 11500);
DISPLAY 0.617021 (-4850 11500);
PAINT SKYBLUE (-4850 11500);
FORCEPROP 1 LAST MATERIAL X7R
J 2
(-4850 11475);
DISPLAY 0.617021 (-4850 11475);
PAINT SKYBLUE (-4850 11475);
FORCEPROP 1 LAST LOCATION PC446
J 2
(-4850 11575);
DISPLAY 0.617021 (-4850 11575);
PAINT AQUA (-4850 11575);
FORCEPROP 1 LASTPIN (-4800 11600) $PN 1
J 2
(-4810 11580);
DISPLAY 0.617021 (-4810 11580);
FORCEPROP 1 LASTPIN (-4800 11400) $PN 2
J 2
(-4810 11380);
DISPLAY 0.617021 (-4810 11380);
FORCEPROP 2 LAST CDS_LIB pure_quanta
J 2
(-4800 11500);
PAINT MONO (-4800 11500);
DISPLAY INVISIBLE (-4800 11500);
FORCEPROP 1 LAST PATH I52
J 2
(-4850 11650);
DISPLAY 0.978723 (-4850 11650);
PAINT WHITE (-4850 11650);
DISPLAY INVISIBLE (-4850 11650);
FORCEPROP 2 LAST $SEC 1
J 0
(-4850 11700);
DISPLAY 0.680851 (-4850 11700);
PAINT MONO (-4850 11700);
DISPLAY INVISIBLE (-4850 11700);
FORCEPROP 2 LAST CDS_SEC 1
J 0
(-4850 11700);
DISPLAY 1.021277 (-4850 11700);
DISPLAY INVISIBLE (-4850 11700);
FORCEADD Q_CAP..1
(-4975 12125);
FORCEPROP 1 LAST PART_NUMBER CH6223MEA01
J 0
(-4925 11975);
DISPLAY 0.617021 (-4925 11975);
PAINT BLUE (-4925 11975);
DISPLAY INVISIBLE (-4925 11975);
FORCEPROP 1 LAST TOLERANCE 20%
J 0
(-4925 12125);
DISPLAY 0.617021 (-4925 12125);
PAINT SKYBLUE (-4925 12125);
FORCEPROP 1 LAST PACK_TYPE C0805
J 0
(-4925 12025);
DISPLAY 0.617021 (-4925 12025);
PAINT SKYBLUE (-4925 12025);
FORCEPROP 1 LAST VALUE 22UF
J 0
(-4925 12225);
DISPLAY 0.617021 (-4925 12225);
PAINT SKYBLUE (-4925 12225);
FORCEPROP 1 LAST VOLTAGE 16V
J 0
(-4925 12175);
DISPLAY 0.617021 (-4925 12175);
PAINT SKYBLUE (-4925 12175);
FORCEPROP 1 LAST MATERIAL X6S
J 0
(-4925 12075);
DISPLAY 0.617021 (-4925 12075);
PAINT SKYBLUE (-4925 12075);
FORCEPROP 1 LAST LOCATION PC450_P1_1
J 0
(-4925 12275);
DISPLAY 0.617021 (-4925 12275);
PAINT AQUA (-4925 12275);
FORCEPROP 1 LASTPIN (-4975 12225) $PN 1
J 0
(-4965 12205);
DISPLAY 0.617021 (-4965 12205);
PAINT MONO (-4965 12205);
FORCEPROP 1 LASTPIN (-4975 12025) $PN 2
J 0
(-4965 12005);
DISPLAY 0.617021 (-4965 12005);
PAINT MONO (-4965 12005);
FORCEPROP 2 LAST CDS_LIB pure_quanta
J 0
(-4975 12125);
DISPLAY INVISIBLE (-4975 12125);
FORCEPROP 1 LAST PATH I53
J 0
(-4925 12275);
DISPLAY 0.978723 (-4925 12275);
PAINT WHITE (-4925 12275);
DISPLAY INVISIBLE (-4925 12275);
FORCEPROP 1 LAST LOCATION PC450_P1_1
J 0
(-4925 12325);
DISPLAY 1.021277 (-4925 12325);
PAINT AQUA (-4925 12325);
DISPLAY INVISIBLE (-4925 12325);
FORCEPROP 0 LAST $SEC 1
J 0
(-4925 12325);
DISPLAY 0.680851 (-4925 12325);
PAINT MONO (-4925 12325);
DISPLAY INVISIBLE (-4925 12325);
FORCEPROP 0 LAST CDS_SEC 1
J 0
(-4925 12325);
DISPLAY 1.021277 (-4925 12325);
DISPLAY INVISIBLE (-4925 12325);
FORCEADD Q_INDUCTOR..1
(-4575 11250);
FORCEPROP 1 LAST PART_NUMBER CV+12^0EZ03
J 0
(-4700 11360);
DISPLAY 0.617021 (-4700 11360);
PAINT BLUE (-4700 11360);
DISPLAY INVISIBLE (-4700 11360);
FORCEPROP 1 LAST MATERIAL IND
J 0
(-4700 11305);
DISPLAY 0.617021 (-4700 11305);
PAINT SKYBLUE (-4700 11305);
FORCEPROP 2 LAST PACK_TYPE SMLF
J 0
(-4700 11450);
DISPLAY 0.617021 (-4700 11450);
PAINT SKYBLUE (-4700 11450);
FORCEPROP 2 LAST VALUE 120NH/69A
J 0
(-4700 11500);
DISPLAY 0.617021 (-4700 11500);
PAINT SKYBLUE (-4700 11500);
FORCEPROP 1 LAST LOCATION PL21
J 0
(-4700 11410);
DISPLAY 0.617021 (-4700 11410);
PAINT AQUA (-4700 11410);
FORCEPROP 0 LASTPIN (-4675 11225) $PN 1
J 2
(-4685 11235);
DISPLAY 0.617021 (-4685 11235);
PAINT MONO (-4685 11235);
FORCEPROP 0 LASTPIN (-4475 11225) $PN 2
J 0
(-4465 11235);
DISPLAY 0.617021 (-4465 11235);
PAINT MONO (-4465 11235);
FORCEPROP 1 LAST NEEDS_NO_SIZE TRUE
J 0
(-4575 11250);
DISPLAY 0.468085 (-4575 11250);
PAINT GREEN (-4575 11250);
DISPLAY INVISIBLE (-4575 11250);
FORCEPROP 2 LAST CDS_LIB pure_quanta
J 0
(-4575 11250);
DISPLAY INVISIBLE (-4575 11250);
FORCEPROP 1 LAST PATH I54
J 0
(-4500 11305);
DISPLAY 0.723404 (-4500 11305);
PAINT GREEN (-4500 11305);
DISPLAY INVISIBLE (-4500 11305);
FORCEPROP 0 LAST $SEC 1
J 0
(-4700 11550);
DISPLAY 0.680851 (-4700 11550);
PAINT MONO (-4700 11550);
DISPLAY INVISIBLE (-4700 11550);
FORCEPROP 0 LAST CDS_SEC 1
J 0
(-4700 11550);
DISPLAY 1.021277 (-4700 11550);
DISPLAY INVISIBLE (-4700 11550);
FORCEADD Q_CAP..1
(-3925 11025);
FORCEPROP 1 LAST PART_NUMBER CH4106K1B01
J 0
(-3875 10850);
DISPLAY 0.617021 (-3875 10850);
PAINT BLUE (-3875 10850);
DISPLAY INVISIBLE (-3875 10850);
FORCEPROP 1 LAST PACK_TYPE C0402
J 0
(-3875 10900);
DISPLAY 0.617021 (-3875 10900);
PAINT SKYBLUE (-3875 10900);
FORCEPROP 1 LAST VALUE 100NF
J 0
(-3875 11100);
DISPLAY 0.617021 (-3875 11100);
PAINT SKYBLUE (-3875 11100);
FORCEPROP 1 LAST VOLTAGE 50V
J 0
(-3875 11050);
DISPLAY 0.617021 (-3875 11050);
PAINT SKYBLUE (-3875 11050);
FORCEPROP 1 LAST TOLERANCE 10%
J 0
(-3875 11000);
DISPLAY 0.617021 (-3875 11000);
PAINT SKYBLUE (-3875 11000);
FORCEPROP 1 LAST MATERIAL X7R
J 0
(-3875 10950);
DISPLAY 0.617021 (-3875 10950);
PAINT SKYBLUE (-3875 10950);
FORCEPROP 1 LAST LOCATION PC452_P1_1
J 0
(-3875 11150);
DISPLAY 0.617021 (-3875 11150);
PAINT AQUA (-3875 11150);
FORCEPROP 1 LASTPIN (-3925 11125) $PN 1
J 0
(-3915 11105);
DISPLAY 0.617021 (-3915 11105);
PAINT MONO (-3915 11105);
FORCEPROP 1 LASTPIN (-3925 10925) $PN 2
J 0
(-3915 10905);
DISPLAY 0.617021 (-3915 10905);
PAINT MONO (-3915 10905);
FORCEPROP 2 LAST CDS_LIB pure_quanta
J 0
(-3925 11025);
DISPLAY INVISIBLE (-3925 11025);
FORCEPROP 1 LAST PATH I55
J 0
(-3875 11175);
DISPLAY 0.978723 (-3875 11175);
PAINT WHITE (-3875 11175);
DISPLAY INVISIBLE (-3875 11175);
FORCEPROP 1 LAST LOCATION PC452_P1_1
J 0
(-3875 11200);
DISPLAY 1.021277 (-3875 11200);
PAINT AQUA (-3875 11200);
DISPLAY INVISIBLE (-3875 11200);
FORCEPROP 0 LAST $SEC 1
J 0
(-3875 11200);
DISPLAY 0.680851 (-3875 11200);
PAINT MONO (-3875 11200);
DISPLAY INVISIBLE (-3875 11200);
FORCEPROP 0 LAST CDS_SEC 1
J 0
(-3875 11200);
DISPLAY 1.021277 (-3875 11200);
DISPLAY INVISIBLE (-3875 11200);
FORCEADD UNIVERSAL_GND..1
(-4375 11700);
FORCEPROP 3 LASTPIN (-4375 11750) SIG_NAME GND\g
J 0
(-4365 11760);
DISPLAY 0.659574 (-4365 11760);
PAINT MONO (-4365 11760);
DISPLAY INVISIBLE (-4365 11760);
FORCEPROP 1 LAST HDL_POWER GND
J 1
(-4350 11625);
DISPLAY 0.872340 (-4350 11625);
PAINT GREEN (-4350 11625);
DISPLAY INVISIBLE (-4350 11625);
FORCEPROP 2 LAST CDS_LIB logical_power
J 0
(-4375 11700);
PAINT MONO (-4375 11700);
DISPLAY INVISIBLE (-4375 11700);
FORCEPROP 1 LAST PATH I56
J 0
(-4300 11700);
DISPLAY 0.872340 (-4300 11700);
PAINT AQUA (-4300 11700);
DISPLAY INVISIBLE (-4300 11700);
FORCEADD VCC15..1
(-4375 12500);
FORCEPROP 3 LASTPIN (-4375 12450) SIG_NAME SW_P12V_PVCCINFAON_CPU1_FLT\g
J 0
(-4365 12460);
DISPLAY 0.659574 (-4365 12460);
PAINT MONO (-4365 12460);
DISPLAY INVISIBLE (-4365 12460);
FORCEPROP 1 LAST HDL_POWER SW_P12V_PVCCINFAON_CPU1_FLT
J 1
(-4325 12550);
DISPLAY 0.617021 (-4325 12550);
PAINT GREEN (-4325 12550);
FORCEPROP 2 LAST CDS_LIB logical_power
J 0
(-4375 12500);
DISPLAY INVISIBLE (-4375 12500);
FORCEPROP 1 LAST PATH I57
J 0
(-4325 12525);
DISPLAY 0.872340 (-4325 12525);
PAINT AQUA (-4325 12525);
DISPLAY INVISIBLE (-4325 12525);
FORCEADD VCC15..1
(-2425 8575);
FORCEPROP 3 LASTPIN (-2425 8525) SIG_NAME PVCCINFAON_CPU1\g
J 0
(-2415 8535);
DISPLAY 0.659574 (-2415 8535);
PAINT MONO (-2415 8535);
DISPLAY INVISIBLE (-2415 8535);
FORCEPROP 1 LAST HDL_POWER PVCCINFAON_CPU1
J 1
(-2425 8625);
DISPLAY 0.617021 (-2425 8625);
PAINT GREEN (-2425 8625);
FORCEPROP 2 LAST CDS_LIB logical_power
J 0
(-2425 8575);
DISPLAY INVISIBLE (-2425 8575);
FORCEPROP 1 LAST PATH I58
J 0
(-2375 8600);
DISPLAY 0.872340 (-2375 8600);
PAINT AQUA (-2375 8600);
DISPLAY INVISIBLE (-2375 8600);
FORCEADD Q_CAPP..1
(-2475 9225);
FORCEPROP 1 LAST PART_NUMBER CC7560JMD16
J 0
(-2425 9025);
DISPLAY 0.617021 (-2425 9025);
PAINT BLUE (-2425 9025);
DISPLAY INVISIBLE (-2425 9025);
FORCEPROP 1 LAST PACK_TYPE THLF
J 0
(-2425 9075);
DISPLAY 0.617021 (-2425 9075);
PAINT SKYBLUE (-2425 9075);
FORCEPROP 1 LAST VALUE 560UF
J 0
(-2425 9275);
DISPLAY 0.617021 (-2425 9275);
PAINT SKYBLUE (-2425 9275);
FORCEPROP 1 LAST TOLERANCE 20%
J 0
(-2425 9225);
DISPLAY 0.617021 (-2425 9225);
PAINT SKYBLUE (-2425 9225);
FORCEPROP 1 LAST MATERIAL OSCON
J 0
(-2425 9125);
DISPLAY 0.617021 (-2425 9125);
PAINT SKYBLUE (-2425 9125);
FORCEPROP 1 LAST VOLTAGE 2.5V
J 0
(-2425 9175);
DISPLAY 0.617021 (-2425 9175);
PAINT SKYBLUE (-2425 9175);
FORCEPROP 1 LAST LOCATION PC1593
J 0
(-2425 9325);
DISPLAY 0.617021 (-2425 9325);
PAINT AQUA (-2425 9325);
FORCEPROP 1 LASTPIN (-2475 9325) $PN 1
J 0
(-2465 9310);
DISPLAY 0.617021 (-2465 9310);
PAINT MONO (-2465 9310);
FORCEPROP 1 LASTPIN (-2475 9125) $PN 2
J 0
(-2465 9110);
DISPLAY 0.617021 (-2465 9110);
PAINT MONO (-2465 9110);
FORCEPROP 2 LAST CDS_LIB pure_quanta
J 0
(-2475 9225);
DISPLAY INVISIBLE (-2475 9225);
FORCEPROP 1 LAST PATH I59
J 0
(-2425 9375);
DISPLAY 0.978723 (-2425 9375);
DISPLAY INVISIBLE (-2425 9375);
FORCEPROP 2 LAST $SEC 1
J 0
(-2425 9425);
DISPLAY 0.680851 (-2425 9425);
PAINT MONO (-2425 9425);
DISPLAY INVISIBLE (-2425 9425);
FORCEPROP 2 LAST CDS_SEC 1
J 0
(-2425 9425);
DISPLAY 1.021277 (-2425 9425);
DISPLAY INVISIBLE (-2425 9425);
FORCEADD Q_CAP..2
(-8325 8250);
FORCEPROP 1 LAST PART_NUMBER CH4104K1B00
J 1
(-8100 8200);
DISPLAY 0.617021 (-8100 8200);
PAINT BLUE (-8100 8200);
DISPLAY INVISIBLE (-8100 8200);
FORCEPROP 1 LAST TOLERANCE 10%
J 2
(-7800 8250);
DISPLAY 0.617021 (-7800 8250);
PAINT SKYBLUE (-7800 8250);
FORCEPROP 1 LAST VALUE 0.1UF
J 2
(-8450 8200);
DISPLAY 0.617021 (-8450 8200);
PAINT SKYBLUE (-8450 8200);
FORCEPROP 1 LAST MATERIAL X7R
J 0
(-8000 8250);
DISPLAY 0.617021 (-8000 8250);
PAINT SKYBLUE (-8000 8250);
FORCEPROP 1 LAST PACK_TYPE 0402
J 1
(-8125 8250);
DISPLAY 0.617021 (-8125 8250);
PAINT SKYBLUE (-8125 8250);
FORCEPROP 1 LAST VOLTAGE 25V
J 0
(-8425 8200);
DISPLAY 0.617021 (-8425 8200);
PAINT SKYBLUE (-8425 8200);
FORCEPROP 1 LAST LOCATION PC1365
J 1
(-8525 8250);
DISPLAY 0.617021 (-8525 8250);
PAINT AQUA (-8525 8250);
FORCEPROP 1 LASTPIN (-8425 8250) $PN 1
J 0
(-8435 8265);
DISPLAY 0.617021 (-8435 8265);
FORCEPROP 1 LASTPIN (-8225 8250) $PN 2
J 0
(-8240 8265);
DISPLAY 0.617021 (-8240 8265);
FORCEPROP 2 LAST CDS_LIB pure_quanta
J 0
(-8325 8250);
PAINT MONO (-8325 8250);
DISPLAY INVISIBLE (-8325 8250);
FORCEPROP 1 LAST PATH I6
J 0
(-8325 8450);
DISPLAY 0.978723 (-8325 8450);
PAINT WHITE (-8325 8450);
DISPLAY INVISIBLE (-8325 8450);
FORCEPROP 2 LAST $SEC 1
J 0
(-8325 8500);
DISPLAY 0.680851 (-8325 8500);
PAINT MONO (-8325 8500);
DISPLAY INVISIBLE (-8325 8500);
FORCEPROP 2 LAST CDS_SEC 1
J 0
(-8325 8500);
DISPLAY 1.021277 (-8325 8500);
DISPLAY INVISIBLE (-8325 8500);
FORCEADD Q_CAPP..1
(-1900 9225);
FORCEPROP 1 LAST PART_NUMBER CC7560JMD16
J 0
(-1850 9025);
DISPLAY 0.617021 (-1850 9025);
PAINT BLUE (-1850 9025);
DISPLAY INVISIBLE (-1850 9025);
FORCEPROP 1 LAST PACK_TYPE THLF
J 0
(-1850 9075);
DISPLAY 0.617021 (-1850 9075);
PAINT SKYBLUE (-1850 9075);
FORCEPROP 1 LAST VALUE 560UF
J 0
(-1850 9275);
DISPLAY 0.617021 (-1850 9275);
PAINT SKYBLUE (-1850 9275);
FORCEPROP 1 LAST TOLERANCE 20%
J 0
(-1850 9225);
DISPLAY 0.617021 (-1850 9225);
PAINT SKYBLUE (-1850 9225);
FORCEPROP 1 LAST MATERIAL OSCON
J 0
(-1850 9125);
DISPLAY 0.617021 (-1850 9125);
PAINT SKYBLUE (-1850 9125);
FORCEPROP 1 LAST VOLTAGE 2.5V
J 0
(-1850 9175);
DISPLAY 0.617021 (-1850 9175);
PAINT SKYBLUE (-1850 9175);
FORCEPROP 1 LAST LOCATION PC1595
J 0
(-1850 9325);
DISPLAY 0.617021 (-1850 9325);
PAINT AQUA (-1850 9325);
FORCEPROP 1 LASTPIN (-1900 9325) $PN 1
J 0
(-1890 9310);
DISPLAY 0.617021 (-1890 9310);
PAINT MONO (-1890 9310);
FORCEPROP 1 LASTPIN (-1900 9125) $PN 2
J 0
(-1890 9110);
DISPLAY 0.617021 (-1890 9110);
PAINT MONO (-1890 9110);
FORCEPROP 2 LAST CDS_LIB pure_quanta
J 0
(-1900 9225);
DISPLAY INVISIBLE (-1900 9225);
FORCEPROP 1 LAST PATH I60
J 0
(-1850 9375);
DISPLAY 0.978723 (-1850 9375);
DISPLAY INVISIBLE (-1850 9375);
FORCEPROP 2 LAST $SEC 1
J 0
(-1850 9425);
DISPLAY 0.680851 (-1850 9425);
PAINT MONO (-1850 9425);
DISPLAY INVISIBLE (-1850 9425);
FORCEPROP 2 LAST CDS_SEC 1
J 0
(-1850 9425);
DISPLAY 1.021277 (-1850 9425);
DISPLAY INVISIBLE (-1850 9425);
FORCEADD Q_CAPP..1
(-2475 10150);
FORCEPROP 1 LAST PART_NUMBER CH733RY8807
J 0
(-2425 9950);
DISPLAY 0.617021 (-2425 9950);
PAINT BLUE (-2425 9950);
DISPLAY INVISIBLE (-2425 9950);
FORCEPROP 1 LAST PACK_TYPE SMLF
J 0
(-2425 10000);
DISPLAY 0.617021 (-2425 10000);
PAINT SKYBLUE (-2425 10000);
FORCEPROP 1 LAST MATERIAL SPCAP
J 0
(-2425 10050);
DISPLAY 0.617021 (-2425 10050);
PAINT SKYBLUE (-2425 10050);
FORCEPROP 1 LAST VOLTAGE 2V
J 0
(-2425 10100);
DISPLAY 0.617021 (-2425 10100);
PAINT SKYBLUE (-2425 10100);
FORCEPROP 1 LAST TOLERANCE 35%
J 0
(-2425 10150);
DISPLAY 0.617021 (-2425 10150);
PAINT SKYBLUE (-2425 10150);
FORCEPROP 1 LAST VALUE 330UF
J 0
(-2425 10200);
DISPLAY 0.617021 (-2425 10200);
PAINT SKYBLUE (-2425 10200);
FORCEPROP 1 LAST LOCATION PC1588
J 0
(-2425 10250);
DISPLAY 0.617021 (-2425 10250);
PAINT AQUA (-2425 10250);
FORCEPROP 1 LASTPIN (-2475 10250) $PN 1
J 0
(-2465 10235);
DISPLAY 0.617021 (-2465 10235);
PAINT MONO (-2465 10235);
FORCEPROP 1 LASTPIN (-2475 10050) $PN 2
J 0
(-2465 10035);
DISPLAY 0.617021 (-2465 10035);
PAINT MONO (-2465 10035);
FORCEPROP 2 LAST CDS_LIB pure_quanta
J 0
(-2475 10150);
DISPLAY INVISIBLE (-2475 10150);
FORCEPROP 1 LAST PATH I61
J 0
(-2425 10300);
DISPLAY 0.978723 (-2425 10300);
DISPLAY INVISIBLE (-2425 10300);
FORCEPROP 2 LAST $SEC 1
J 0
(-2425 10350);
DISPLAY 0.680851 (-2425 10350);
PAINT MONO (-2425 10350);
DISPLAY INVISIBLE (-2425 10350);
FORCEPROP 2 LAST CDS_SEC 1
J 0
(-2425 10350);
DISPLAY 1.021277 (-2425 10350);
DISPLAY INVISIBLE (-2425 10350);
FORCEADD Q_CAPP..1
(-1900 10150);
FORCEPROP 1 LAST PART_NUMBER CH733RY8807
J 0
(-1850 9950);
DISPLAY 0.617021 (-1850 9950);
PAINT BLUE (-1850 9950);
DISPLAY INVISIBLE (-1850 9950);
FORCEPROP 1 LAST PACK_TYPE SMLF
J 0
(-1850 10000);
DISPLAY 0.617021 (-1850 10000);
PAINT SKYBLUE (-1850 10000);
FORCEPROP 1 LAST VOLTAGE 2V
J 0
(-1850 10100);
DISPLAY 0.617021 (-1850 10100);
PAINT SKYBLUE (-1850 10100);
FORCEPROP 1 LAST VALUE 330UF
J 0
(-1850 10200);
DISPLAY 0.617021 (-1850 10200);
PAINT SKYBLUE (-1850 10200);
FORCEPROP 1 LAST TOLERANCE 35%
J 0
(-1850 10150);
DISPLAY 0.617021 (-1850 10150);
PAINT SKYBLUE (-1850 10150);
FORCEPROP 1 LAST MATERIAL SPCAP
J 0
(-1850 10050);
DISPLAY 0.617021 (-1850 10050);
PAINT SKYBLUE (-1850 10050);
FORCEPROP 1 LAST LOCATION PC1594
J 0
(-1850 10250);
DISPLAY 0.617021 (-1850 10250);
PAINT AQUA (-1850 10250);
FORCEPROP 1 LASTPIN (-1900 10250) $PN 1
J 0
(-1890 10235);
DISPLAY 0.617021 (-1890 10235);
PAINT MONO (-1890 10235);
FORCEPROP 1 LASTPIN (-1900 10050) $PN 2
J 0
(-1890 10035);
DISPLAY 0.617021 (-1890 10035);
PAINT MONO (-1890 10035);
FORCEPROP 2 LAST CDS_LIB pure_quanta
J 0
(-1900 10150);
DISPLAY INVISIBLE (-1900 10150);
FORCEPROP 1 LAST PATH I62
J 0
(-1850 10300);
DISPLAY 0.978723 (-1850 10300);
DISPLAY INVISIBLE (-1850 10300);
FORCEPROP 2 LAST $SEC 1
J 0
(-1850 10350);
DISPLAY 0.680851 (-1850 10350);
PAINT MONO (-1850 10350);
DISPLAY INVISIBLE (-1850 10350);
FORCEPROP 2 LAST CDS_SEC 1
J 0
(-1850 10350);
DISPLAY 1.021277 (-1850 10350);
DISPLAY INVISIBLE (-1850 10350);
FORCEADD Q_CAP..1
(-3525 11025);
FORCEPROP 1 LAST PART_NUMBER CH622KMEA03
J 0
(-3475 10850);
DISPLAY 0.617021 (-3475 10850);
PAINT BLUE (-3475 10850);
DISPLAY INVISIBLE (-3475 10850);
FORCEPROP 1 LAST TOLERANCE 20%
J 0
(-3475 11000);
DISPLAY 0.617021 (-3475 11000);
PAINT SKYBLUE (-3475 11000);
FORCEPROP 1 LAST PACK_TYPE C0805
J 0
(-3475 10900);
DISPLAY 0.617021 (-3475 10900);
PAINT SKYBLUE (-3475 10900);
FORCEPROP 1 LAST MATERIAL X6S
J 0
(-3475 10950);
DISPLAY 0.617021 (-3475 10950);
PAINT SKYBLUE (-3475 10950);
FORCEPROP 1 LAST VALUE 22UF
J 0
(-3475 11100);
DISPLAY 0.617021 (-3475 11100);
PAINT SKYBLUE (-3475 11100);
FORCEPROP 1 LAST VOLTAGE 4V
J 0
(-3475 11050);
DISPLAY 0.617021 (-3475 11050);
PAINT SKYBLUE (-3475 11050);
FORCEPROP 1 LAST LOCATION PC455_P1_1
J 0
(-3475 11150);
DISPLAY 0.617021 (-3475 11150);
PAINT AQUA (-3475 11150);
FORCEPROP 1 LASTPIN (-3525 11125) $PN 1
J 0
(-3515 11105);
DISPLAY 0.617021 (-3515 11105);
PAINT MONO (-3515 11105);
FORCEPROP 1 LASTPIN (-3525 10925) $PN 2
J 0
(-3515 10905);
DISPLAY 0.617021 (-3515 10905);
PAINT MONO (-3515 10905);
FORCEPROP 2 LAST CDS_LIB pure_quanta
J 0
(-3525 11025);
DISPLAY INVISIBLE (-3525 11025);
FORCEPROP 1 LAST PATH I63
J 0
(-3475 11175);
DISPLAY 0.978723 (-3475 11175);
PAINT WHITE (-3475 11175);
DISPLAY INVISIBLE (-3475 11175);
FORCEPROP 1 LAST LOCATION PC455_P1_1
J 0
(-3475 11200);
DISPLAY 1.021277 (-3475 11200);
PAINT AQUA (-3475 11200);
DISPLAY INVISIBLE (-3475 11200);
FORCEPROP 0 LAST $SEC 1
J 0
(-3475 11200);
DISPLAY 0.680851 (-3475 11200);
PAINT MONO (-3475 11200);
DISPLAY INVISIBLE (-3475 11200);
FORCEPROP 0 LAST CDS_SEC 1
J 0
(-3475 11200);
DISPLAY 1.021277 (-3475 11200);
DISPLAY INVISIBLE (-3475 11200);
FORCEADD UNIVERSAL_GND..1
(-2800 10650);
FORCEPROP 3 LASTPIN (-2800 10700) SIG_NAME GND\g
J 0
(-2790 10710);
DISPLAY 0.659574 (-2790 10710);
PAINT MONO (-2790 10710);
DISPLAY INVISIBLE (-2790 10710);
FORCEPROP 1 LAST HDL_POWER GND
J 1
(-2775 10575);
DISPLAY 0.872340 (-2775 10575);
PAINT GREEN (-2775 10575);
DISPLAY INVISIBLE (-2775 10575);
FORCEPROP 2 LAST CDS_LIB logical_power
J 0
(-2800 10650);
PAINT MONO (-2800 10650);
DISPLAY INVISIBLE (-2800 10650);
FORCEPROP 1 LAST PATH I64
J 0
(-2725 10650);
DISPLAY 0.872340 (-2725 10650);
PAINT AQUA (-2725 10650);
DISPLAY INVISIBLE (-2725 10650);
FORCEADD Q_CAP..1
(-3100 11025);
FORCEPROP 1 LAST PART_NUMBER CH622KMEA03
J 0
(-3050 10850);
DISPLAY 0.617021 (-3050 10850);
PAINT BLUE (-3050 10850);
DISPLAY INVISIBLE (-3050 10850);
FORCEPROP 1 LAST TOLERANCE 20%
J 0
(-3050 11000);
DISPLAY 0.617021 (-3050 11000);
PAINT SKYBLUE (-3050 11000);
FORCEPROP 1 LAST MATERIAL X6S
J 0
(-3050 10950);
DISPLAY 0.617021 (-3050 10950);
PAINT SKYBLUE (-3050 10950);
FORCEPROP 1 LAST PACK_TYPE C0805
J 0
(-3050 10900);
DISPLAY 0.617021 (-3050 10900);
PAINT SKYBLUE (-3050 10900);
FORCEPROP 1 LAST VALUE 22UF
J 0
(-3050 11100);
DISPLAY 0.617021 (-3050 11100);
PAINT SKYBLUE (-3050 11100);
FORCEPROP 1 LAST VOLTAGE 4V
J 0
(-3050 11050);
DISPLAY 0.617021 (-3050 11050);
PAINT SKYBLUE (-3050 11050);
FORCEPROP 1 LAST LOCATION PC457_P1_1
J 0
(-3050 11150);
DISPLAY 0.617021 (-3050 11150);
PAINT AQUA (-3050 11150);
FORCEPROP 1 LASTPIN (-3100 11125) $PN 1
J 0
(-3090 11105);
DISPLAY 0.617021 (-3090 11105);
PAINT MONO (-3090 11105);
FORCEPROP 1 LASTPIN (-3100 10925) $PN 2
J 0
(-3090 10905);
DISPLAY 0.617021 (-3090 10905);
PAINT MONO (-3090 10905);
FORCEPROP 2 LAST CDS_LIB pure_quanta
J 0
(-3100 11025);
DISPLAY INVISIBLE (-3100 11025);
FORCEPROP 1 LAST PATH I65
J 0
(-3050 11175);
DISPLAY 0.978723 (-3050 11175);
PAINT WHITE (-3050 11175);
DISPLAY INVISIBLE (-3050 11175);
FORCEPROP 1 LAST LOCATION PC457_P1_1
J 0
(-3050 11200);
DISPLAY 1.021277 (-3050 11200);
PAINT AQUA (-3050 11200);
DISPLAY INVISIBLE (-3050 11200);
FORCEPROP 0 LAST $SEC 1
J 0
(-3050 11200);
DISPLAY 0.680851 (-3050 11200);
PAINT MONO (-3050 11200);
DISPLAY INVISIBLE (-3050 11200);
FORCEPROP 0 LAST CDS_SEC 1
J 0
(-3050 11200);
DISPLAY 1.021277 (-3050 11200);
DISPLAY INVISIBLE (-3050 11200);
FORCEADD VCC15..1
(-2800 11425);
FORCEPROP 3 LASTPIN (-2800 11375) SIG_NAME PVCCINFAON_CPU1\g
J 0
(-2790 11385);
DISPLAY 0.659574 (-2790 11385);
PAINT MONO (-2790 11385);
DISPLAY INVISIBLE (-2790 11385);
FORCEPROP 1 LAST HDL_POWER PVCCINFAON_CPU1
J 1
(-2800 11475);
DISPLAY 0.617021 (-2800 11475);
PAINT GREEN (-2800 11475);
FORCEPROP 2 LAST CDS_LIB logical_power
J 0
(-2800 11425);
DISPLAY INVISIBLE (-2800 11425);
FORCEPROP 1 LAST PATH I66
J 0
(-2750 11450);
DISPLAY 0.872340 (-2750 11450);
PAINT AQUA (-2750 11450);
DISPLAY INVISIBLE (-2750 11450);
FORCEADD GND..1
(-3125 12100);
FORCEPROP 3 LASTPIN (-3125 12150) SIG_NAME GND\g
J 0
(-3115 12160);
DISPLAY 0.659574 (-3115 12160);
PAINT MONO (-3115 12160);
DISPLAY INVISIBLE (-3115 12160);
FORCEPROP 1 LAST HDL_POWER GND
J 0
(-3125 12250);
DISPLAY 0.872340 (-3125 12250);
PAINT GREEN (-3125 12250);
DISPLAY INVISIBLE (-3125 12250);
FORCEPROP 1 LAST SIZE 1B
J 0
(-3050 12050);
DISPLAY 0.872340 (-3050 12050);
PAINT AQUA (-3050 12050);
DISPLAY INVISIBLE (-3050 12050);
FORCEPROP 2 LAST CDS_LIB logical_power
J 0
(-3125 12100);
DISPLAY INVISIBLE (-3125 12100);
FORCEPROP 1 LAST PATH I67
J 0
(-3050 12100);
DISPLAY 0.872340 (-3050 12100);
PAINT AQUA (-3050 12100);
DISPLAY INVISIBLE (-3050 12100);
FORCEADD Q_CAP..1
(-3125 12350);
FORCEPROP 1 LAST PART_NUMBER CH4106K1B01
J 0
(-3075 12200);
DISPLAY 0.787234 (-3075 12200);
DISPLAY INVISIBLE (-3075 12200);
FORCEPROP 1 LAST PACK_TYPE C0402
J 0
(-3075 12150);
DISPLAY 0.787234 (-3075 12150);
FORCEPROP 1 LAST MATERIAL X7R
J 0
(-3075 12250);
DISPLAY 0.787234 (-3075 12250);
FORCEPROP 1 LAST TOLERANCE 10%
J 0
(-3075 12300);
DISPLAY 0.787234 (-3075 12300);
FORCEPROP 1 LAST VALUE 100NF
J 0
(-3075 12400);
DISPLAY 0.787234 (-3075 12400);
FORCEPROP 1 LAST VOLTAGE 50V
J 0
(-3075 12350);
DISPLAY 0.787234 (-3075 12350);
FORCEPROP 1 LAST LOCATION PC1659
J 0
(-3075 12450);
DISPLAY 0.787234 (-3075 12450);
FORCEPROP 1 LASTPIN (-3125 12450) $PN 1
J 0
(-3115 12430);
DISPLAY 0.787234 (-3115 12430);
PAINT MONO (-3115 12430);
FORCEPROP 1 LASTPIN (-3125 12250) $PN 2
J 0
(-3115 12230);
DISPLAY 0.787234 (-3115 12230);
PAINT MONO (-3115 12230);
FORCEPROP 2 LAST CDS_LIB pure_quanta
J 0
(-3125 12350);
DISPLAY INVISIBLE (-3125 12350);
FORCEPROP 1 LAST PATH I68
J 0
(-3075 12500);
DISPLAY 0.978723 (-3075 12500);
PAINT WHITE (-3075 12500);
DISPLAY INVISIBLE (-3075 12500);
FORCEPROP 0 LAST $SEC 1
J 0
(-3075 12500);
DISPLAY 0.680851 (-3075 12500);
PAINT MONO (-3075 12500);
DISPLAY INVISIBLE (-3075 12500);
FORCEPROP 0 LAST CDS_SEC 1
J 0
(-3075 12500);
DISPLAY 1.021277 (-3075 12500);
DISPLAY INVISIBLE (-3075 12500);
FORCEADD Q_CAPP..1
(-2375 12350);
FORCEPROP 1 LAST PART_NUMBER CC72703MD38
J 0
(-2325 12175);
DISPLAY 0.617021 (-2325 12175);
PAINT BLUE (-2325 12175);
DISPLAY INVISIBLE (-2325 12175);
FORCEPROP 1 LAST PACK_TYPE THLF
J 0
(-2325 12225);
DISPLAY 0.617021 (-2325 12225);
PAINT SKYBLUE (-2325 12225);
FORCEPROP 1 LAST TOLERANCE 20%
J 0
(-2325 12375);
DISPLAY 0.617021 (-2325 12375);
PAINT SKYBLUE (-2325 12375);
FORCEPROP 1 LAST MATERIAL OSCON
J 0
(-2325 12275);
DISPLAY 0.617021 (-2325 12275);
PAINT SKYBLUE (-2325 12275);
FORCEPROP 1 LAST VOLTAGE 16V
J 0
(-2325 12325);
DISPLAY 0.617021 (-2325 12325);
PAINT SKYBLUE (-2325 12325);
FORCEPROP 1 LAST VALUE 270UF
J 0
(-2325 12425);
DISPLAY 0.617021 (-2325 12425);
PAINT SKYBLUE (-2325 12425);
FORCEPROP 1 LAST LOCATION PC460
J 0
(-2325 12475);
DISPLAY 0.617021 (-2325 12475);
PAINT AQUA (-2325 12475);
FORCEPROP 1 LASTPIN (-2375 12450) $PN 1
J 0
(-2365 12435);
DISPLAY 0.617021 (-2365 12435);
PAINT MONO (-2365 12435);
FORCEPROP 1 LASTPIN (-2375 12250) $PN 2
J 0
(-2365 12235);
DISPLAY 0.617021 (-2365 12235);
PAINT MONO (-2365 12235);
FORCEPROP 2 LAST CDS_LIB pure_quanta
J 0
(-2375 12350);
DISPLAY INVISIBLE (-2375 12350);
FORCEPROP 1 LAST PATH I69
J 0
(-2325 12500);
DISPLAY 0.978723 (-2325 12500);
DISPLAY INVISIBLE (-2325 12500);
FORCEPROP 1 LAST LOCATION PC460
J 0
(-2325 12525);
DISPLAY 1.021277 (-2325 12525);
PAINT AQUA (-2325 12525);
DISPLAY INVISIBLE (-2325 12525);
FORCEPROP 0 LAST $SEC 1
J 0
(-2325 12525);
DISPLAY 0.680851 (-2325 12525);
PAINT MONO (-2325 12525);
DISPLAY INVISIBLE (-2325 12525);
FORCEPROP 0 LAST CDS_SEC 1
J 0
(-2325 12525);
DISPLAY 1.021277 (-2325 12525);
DISPLAY INVISIBLE (-2325 12525);
FORCEADD OFFPAGE..5
(-8425 8425);
FORCEPROP 2 LAST $XR0 292 
J 0
(-8710 8425);
DISPLAY 0.638298 (-8710 8425);
PAINT MONO (-8710 8425);
FORCEPROP 1 LAST COMMENT_BODY TRUE
J 0
(-8325 8350);
DISPLAY 0.872340 (-8325 8350);
PAINT GREEN (-8325 8350);
DISPLAY INVISIBLE (-8325 8350);
FORCEPROP 1 LAST OFFPAGE TRUE
J 0
(-8100 8300);
DISPLAY 0.872340 (-8100 8300);
PAINT GREEN (-8100 8300);
DISPLAY INVISIBLE (-8100 8300);
FORCEPROP 2 LAST CDS_LIB standard
J 0
(-8425 8425);
DISPLAY INVISIBLE (-8425 8425);
FORCEPROP 2 LAST PATH I7
J 0
(-8700 8475);
DISPLAY 1.021277 (-8700 8475);
DISPLAY INVISIBLE (-8700 8475);
FORCEADD Q_CAPP..1
(-1975 12350);
FORCEPROP 1 LAST PART_NUMBER CC72703MD38
J 0
(-1925 12175);
DISPLAY 0.617021 (-1925 12175);
PAINT BLUE (-1925 12175);
DISPLAY INVISIBLE (-1925 12175);
FORCEPROP 1 LAST PACK_TYPE THLF
J 0
(-1925 12225);
DISPLAY 0.617021 (-1925 12225);
PAINT SKYBLUE (-1925 12225);
FORCEPROP 1 LAST TOLERANCE 20%
J 0
(-1925 12375);
DISPLAY 0.617021 (-1925 12375);
PAINT SKYBLUE (-1925 12375);
FORCEPROP 1 LAST MATERIAL OSCON
J 0
(-1925 12275);
DISPLAY 0.617021 (-1925 12275);
PAINT SKYBLUE (-1925 12275);
FORCEPROP 1 LAST VOLTAGE 16V
J 0
(-1925 12325);
DISPLAY 0.617021 (-1925 12325);
PAINT SKYBLUE (-1925 12325);
FORCEPROP 1 LAST VALUE 270UF
J 0
(-1925 12425);
DISPLAY 0.617021 (-1925 12425);
PAINT SKYBLUE (-1925 12425);
FORCEPROP 1 LAST LOCATION PC461
J 0
(-1925 12475);
DISPLAY 0.617021 (-1925 12475);
PAINT AQUA (-1925 12475);
FORCEPROP 1 LASTPIN (-1975 12450) $PN 1
J 0
(-1965 12435);
DISPLAY 0.617021 (-1965 12435);
PAINT MONO (-1965 12435);
FORCEPROP 1 LASTPIN (-1975 12250) $PN 2
J 0
(-1965 12235);
DISPLAY 0.617021 (-1965 12235);
PAINT MONO (-1965 12235);
FORCEPROP 2 LAST CDS_LIB pure_quanta
J 0
(-1975 12350);
DISPLAY INVISIBLE (-1975 12350);
FORCEPROP 1 LAST PATH I70
J 0
(-1925 12500);
DISPLAY 0.978723 (-1925 12500);
DISPLAY INVISIBLE (-1925 12500);
FORCEPROP 1 LAST LOCATION PC461
J 0
(-1925 12525);
DISPLAY 1.021277 (-1925 12525);
PAINT AQUA (-1925 12525);
DISPLAY INVISIBLE (-1925 12525);
FORCEPROP 0 LAST $SEC 1
J 0
(-1925 12525);
DISPLAY 0.680851 (-1925 12525);
PAINT MONO (-1925 12525);
DISPLAY INVISIBLE (-1925 12525);
FORCEPROP 0 LAST CDS_SEC 1
J 0
(-1925 12525);
DISPLAY 1.021277 (-1925 12525);
DISPLAY INVISIBLE (-1925 12525);
FORCEADD Q_CAPP..1
(-1325 9225);
FORCEPROP 1 LAST PART_NUMBER CC7560JMD16
J 0
(-1275 9025);
DISPLAY 0.617021 (-1275 9025);
PAINT BLUE (-1275 9025);
DISPLAY INVISIBLE (-1275 9025);
FORCEPROP 1 LAST PACK_TYPE THLF
J 0
(-1275 9075);
DISPLAY 0.617021 (-1275 9075);
PAINT SKYBLUE (-1275 9075);
FORCEPROP 1 LAST VALUE 560UF
J 0
(-1275 9275);
DISPLAY 0.617021 (-1275 9275);
PAINT SKYBLUE (-1275 9275);
FORCEPROP 1 LAST TOLERANCE 20%
J 0
(-1275 9225);
DISPLAY 0.617021 (-1275 9225);
PAINT SKYBLUE (-1275 9225);
FORCEPROP 1 LAST MATERIAL OSCON
J 0
(-1275 9125);
DISPLAY 0.617021 (-1275 9125);
PAINT SKYBLUE (-1275 9125);
FORCEPROP 1 LAST VOLTAGE 2.5V
J 0
(-1275 9175);
DISPLAY 0.617021 (-1275 9175);
PAINT SKYBLUE (-1275 9175);
FORCEPROP 1 LAST LOCATION PC1596
J 0
(-1275 9325);
DISPLAY 0.617021 (-1275 9325);
PAINT AQUA (-1275 9325);
FORCEPROP 1 LASTPIN (-1325 9325) $PN 1
J 0
(-1315 9310);
DISPLAY 0.617021 (-1315 9310);
PAINT MONO (-1315 9310);
FORCEPROP 1 LASTPIN (-1325 9125) $PN 2
J 0
(-1315 9110);
DISPLAY 0.617021 (-1315 9110);
PAINT MONO (-1315 9110);
FORCEPROP 2 LAST CDS_LIB pure_quanta
J 0
(-1325 9225);
DISPLAY INVISIBLE (-1325 9225);
FORCEPROP 1 LAST PATH I71
J 0
(-1275 9375);
DISPLAY 0.978723 (-1275 9375);
DISPLAY INVISIBLE (-1275 9375);
FORCEPROP 2 LAST $SEC 1
J 0
(-1275 9425);
DISPLAY 0.680851 (-1275 9425);
PAINT MONO (-1275 9425);
DISPLAY INVISIBLE (-1275 9425);
FORCEPROP 2 LAST CDS_SEC 1
J 0
(-1275 9425);
DISPLAY 1.021277 (-1275 9425);
DISPLAY INVISIBLE (-1275 9425);
FORCEADD UNIVERSAL_GND..1
(-725 8900);
FORCEPROP 3 LASTPIN (-725 8950) SIG_NAME GND\g
J 0
(-715 8960);
DISPLAY 0.659574 (-715 8960);
PAINT MONO (-715 8960);
DISPLAY INVISIBLE (-715 8960);
FORCEPROP 1 LAST HDL_POWER GND
J 1
(-700 8825);
DISPLAY 0.872340 (-700 8825);
PAINT GREEN (-700 8825);
DISPLAY INVISIBLE (-700 8825);
FORCEPROP 2 LAST CDS_LIB logical_power
J 0
(-725 8900);
PAINT MONO (-725 8900);
DISPLAY INVISIBLE (-725 8900);
FORCEPROP 1 LAST PATH I72
J 0
(-650 8900);
DISPLAY 0.872340 (-650 8900);
PAINT AQUA (-650 8900);
DISPLAY INVISIBLE (-650 8900);
FORCEADD VCC15..1
(-725 9550);
FORCEPROP 3 LASTPIN (-725 9500) SIG_NAME PVCCINFAON_CPU1\g
J 0
(-715 9510);
DISPLAY 0.659574 (-715 9510);
PAINT MONO (-715 9510);
DISPLAY INVISIBLE (-715 9510);
FORCEPROP 1 LAST HDL_POWER PVCCINFAON_CPU1
J 1
(-725 9600);
DISPLAY 0.617021 (-725 9600);
PAINT GREEN (-725 9600);
FORCEPROP 2 LAST CDS_LIB logical_power
J 0
(-725 9550);
DISPLAY INVISIBLE (-725 9550);
FORCEPROP 1 LAST PATH I73
J 0
(-675 9575);
DISPLAY 0.872340 (-675 9575);
PAINT AQUA (-675 9575);
DISPLAY INVISIBLE (-675 9575);
FORCEADD UNIVERSAL_GND..1
(-725 9825);
FORCEPROP 3 LASTPIN (-725 9875) SIG_NAME GND\g
J 0
(-715 9885);
DISPLAY 0.659574 (-715 9885);
PAINT MONO (-715 9885);
DISPLAY INVISIBLE (-715 9885);
FORCEPROP 1 LAST HDL_POWER GND
J 1
(-700 9750);
DISPLAY 0.872340 (-700 9750);
PAINT GREEN (-700 9750);
DISPLAY INVISIBLE (-700 9750);
FORCEPROP 2 LAST CDS_LIB logical_power
J 0
(-725 9825);
PAINT MONO (-725 9825);
DISPLAY INVISIBLE (-725 9825);
FORCEPROP 1 LAST PATH I74
J 0
(-650 9825);
DISPLAY 0.872340 (-650 9825);
PAINT AQUA (-650 9825);
DISPLAY INVISIBLE (-650 9825);
FORCEADD VCC15..1
(-725 10475);
FORCEPROP 3 LASTPIN (-725 10425) SIG_NAME PVCCINFAON_CPU1\g
J 0
(-715 10435);
DISPLAY 0.659574 (-715 10435);
PAINT MONO (-715 10435);
DISPLAY INVISIBLE (-715 10435);
FORCEPROP 1 LAST HDL_POWER PVCCINFAON_CPU1
J 1
(-725 10525);
DISPLAY 0.617021 (-725 10525);
PAINT GREEN (-725 10525);
FORCEPROP 2 LAST CDS_LIB logical_power
J 0
(-725 10475);
DISPLAY INVISIBLE (-725 10475);
FORCEPROP 1 LAST PATH I75
J 0
(-675 10500);
DISPLAY 0.872340 (-675 10500);
PAINT AQUA (-675 10500);
DISPLAY INVISIBLE (-675 10500);
FORCEADD UNIVERSAL_GND..1
(-775 12025);
FORCEPROP 3 LASTPIN (-775 12075) SIG_NAME GND\g
J 0
(-765 12085);
DISPLAY 0.659574 (-765 12085);
PAINT MONO (-765 12085);
DISPLAY INVISIBLE (-765 12085);
FORCEPROP 1 LAST HDL_POWER GND
J 1
(-750 11950);
DISPLAY 0.872340 (-750 11950);
PAINT GREEN (-750 11950);
DISPLAY INVISIBLE (-750 11950);
FORCEPROP 2 LAST CDS_LIB logical_power
J 0
(-775 12025);
PAINT MONO (-775 12025);
DISPLAY INVISIBLE (-775 12025);
FORCEPROP 1 LAST PATH I76
J 0
(-700 12025);
DISPLAY 0.872340 (-700 12025);
PAINT AQUA (-700 12025);
DISPLAY INVISIBLE (-700 12025);
FORCEADD VCC15..1
(-3125 12725);
FORCEPROP 3 LASTPIN (-3125 12675) SIG_NAME P12V_AUX\g
J 0
(-3115 12685);
DISPLAY 0.659574 (-3115 12685);
PAINT MONO (-3115 12685);
DISPLAY INVISIBLE (-3115 12685);
FORCEPROP 1 LAST HDL_POWER P12V_AUX
J 1
(-3125 12775);
DISPLAY 0.617021 (-3125 12775);
PAINT GREEN (-3125 12775);
FORCEPROP 2 LAST CDS_LIB logical_power
J 0
(-3125 12725);
DISPLAY INVISIBLE (-3125 12725);
FORCEPROP 1 LAST PATH I77
J 0
(-3075 12750);
DISPLAY 0.872340 (-3075 12750);
PAINT AQUA (-3075 12750);
DISPLAY INVISIBLE (-3075 12750);
FORCEADD Q_INDUCTOR..1
(-2700 12575);
FORCEPROP 1 LAST PART_NUMBER CV+10G0MZ04
J 0
(-2825 12650);
DISPLAY 0.617021 (-2825 12650);
PAINT BLUE (-2825 12650);
DISPLAY INVISIBLE (-2825 12650);
FORCEPROP 2 LAST PACK_TYPE SMLF
J 0
(-2825 12800);
DISPLAY 0.617021 (-2825 12800);
PAINT SKYBLUE (-2825 12800);
FORCEPROP 2 LAST VALUE 100NH/16A
J 0
(-2825 12750);
DISPLAY 0.617021 (-2825 12750);
PAINT SKYBLUE (-2825 12750);
FORCEPROP 1 LAST MATERIAL IND
J 0
(-2825 12700);
DISPLAY 0.617021 (-2825 12700);
PAINT SKYBLUE (-2825 12700);
FORCEPROP 1 LAST LOCATION PL23
J 0
(-3000 12550);
DISPLAY 0.617021 (-3000 12550);
PAINT AQUA (-3000 12550);
FORCEPROP 0 LASTPIN (-2800 12550) $PN 1
J 2
(-2810 12560);
DISPLAY 0.617021 (-2810 12560);
PAINT MONO (-2810 12560);
FORCEPROP 0 LASTPIN (-2600 12550) $PN 2
J 0
(-2590 12560);
DISPLAY 0.617021 (-2590 12560);
PAINT MONO (-2590 12560);
FORCEPROP 1 LAST NEEDS_NO_SIZE TRUE
J 0
(-2700 12575);
DISPLAY 0.468085 (-2700 12575);
PAINT GREEN (-2700 12575);
DISPLAY INVISIBLE (-2700 12575);
FORCEPROP 2 LAST CDS_LIB pure_quanta
J 0
(-2700 12575);
DISPLAY INVISIBLE (-2700 12575);
FORCEPROP 1 LAST PATH I78
J 0
(-2625 12630);
DISPLAY 0.723404 (-2625 12630);
PAINT GREEN (-2625 12630);
DISPLAY INVISIBLE (-2625 12630);
FORCEPROP 1 LAST LOCATION PL23
J 0
(-2725 12675);
DISPLAY 1.021277 (-2725 12675);
PAINT AQUA (-2725 12675);
DISPLAY INVISIBLE (-2725 12675);
FORCEPROP 0 LAST $SEC 1
J 0
(-2725 12675);
DISPLAY 0.680851 (-2725 12675);
PAINT MONO (-2725 12675);
DISPLAY INVISIBLE (-2725 12675);
FORCEPROP 0 LAST CDS_SEC 1
J 0
(-2725 12675);
DISPLAY 1.021277 (-2725 12675);
DISPLAY INVISIBLE (-2725 12675);
FORCEADD VCC15..1
(-775 12675);
FORCEPROP 3 LASTPIN (-775 12625) SIG_NAME SW_P12V_PVCCINFAON_CPU1_FLT\g
J 0
(-765 12635);
DISPLAY 0.659574 (-765 12635);
PAINT MONO (-765 12635);
DISPLAY INVISIBLE (-765 12635);
FORCEPROP 1 LAST HDL_POWER SW_P12V_PVCCINFAON_CPU1_FLT
J 1
(-825 12725);
DISPLAY 0.617021 (-825 12725);
PAINT GREEN (-825 12725);
FORCEPROP 2 LAST CDS_LIB logical_power
J 0
(-775 12675);
DISPLAY INVISIBLE (-775 12675);
FORCEPROP 1 LAST PATH I79
J 0
(-725 12700);
DISPLAY 0.872340 (-725 12700);
PAINT AQUA (-725 12700);
DISPLAY INVISIBLE (-725 12700);
FORCEADD OFFPAGE..1
(-8425 8325);
FORCEPROP 2 LAST $XR2 294 
J 0
(-8917 8325);
DISPLAY 0.638298 (-8917 8325);
PAINT MONO (-8917 8325);
FORCEPROP 2 LAST $XR1 293 
J 0
(-8797 8325);
DISPLAY 0.638298 (-8797 8325);
PAINT MONO (-8797 8325);
FORCEPROP 2 LAST $XR0 292 
J 0
(-8677 8325);
DISPLAY 0.638298 (-8677 8325);
PAINT MONO (-8677 8325);
FORCEPROP 1 LAST COMMENT_BODY TRUE
J 0
(-8300 8225);
DISPLAY 0.872340 (-8300 8225);
PAINT GREEN (-8300 8225);
DISPLAY INVISIBLE (-8300 8225);
FORCEPROP 1 LAST OFFPAGE TRUE
J 0
(-8100 8200);
DISPLAY 0.872340 (-8100 8200);
PAINT GREEN (-8100 8200);
DISPLAY INVISIBLE (-8100 8200);
FORCEPROP 2 LAST CDS_LIB standard
J 0
(-8425 8325);
DISPLAY INVISIBLE (-8425 8325);
FORCEPROP 2 LAST PATH I8
J 0
(-8675 8375);
DISPLAY 1.021277 (-8675 8375);
DISPLAY INVISIBLE (-8675 8375);
FORCEADD UNIVERSAL_GND..1
(-8500 8625);
FORCEPROP 3 LASTPIN (-8500 8675) SIG_NAME GND\g
J 0
(-8490 8685);
DISPLAY 0.659574 (-8490 8685);
PAINT MONO (-8490 8685);
DISPLAY INVISIBLE (-8490 8685);
FORCEPROP 1 LAST HDL_POWER GND
J 1
(-8475 8550);
DISPLAY 0.872340 (-8475 8550);
PAINT GREEN (-8475 8550);
DISPLAY INVISIBLE (-8475 8550);
FORCEPROP 2 LAST CDS_LIB logical_power
J 0
(-8500 8625);
PAINT MONO (-8500 8625);
DISPLAY INVISIBLE (-8500 8625);
FORCEPROP 1 LAST PATH I9
J 0
(-8425 8625);
DISPLAY 0.872340 (-8425 8625);
PAINT AQUA (-8425 8625);
DISPLAY INVISIBLE (-8425 8625);
FORCEADD DNS..1
(-9000 7825);
PAINT RED (-9000 7825);
FORCEPROP 1 LAST COMMENT_BODY TRUE
R 1
J 0
(-8925 7600);
DISPLAY 0.872340 (-8925 7600);
PAINT GREEN (-8925 7600);
DISPLAY INVISIBLE (-8925 7600);
FORCEPROP 2 LAST CDS_LIB mstr_misc
J 0
(-9000 7825);
DISPLAY INVISIBLE (-9000 7825);
FORCEADD DNS..1
(-9000 10625);
PAINT RED (-9000 10625);
FORCEPROP 1 LAST COMMENT_BODY TRUE
R 1
J 0
(-8925 10400);
DISPLAY 0.872340 (-8925 10400);
PAINT GREEN (-8925 10400);
DISPLAY INVISIBLE (-8925 10400);
FORCEPROP 2 LAST CDS_LIB mstr_misc
J 0
(-9000 10625);
DISPLAY INVISIBLE (-9000 10625);
FORCEADD QUANTA_TITLE_BLOCK_C..1
(-350 6925);
FORCEPROP 0 LAST CDS_CON_LAST_MODIFIED Fri Aug 25 14:05:04 2023
J 0
(-2235 6940);
DISPLAY INVISIBLE (-2235 6940);
FORCEPROP 1 LAST CUSTOM_TXT_CDS <CON_LAST_MODIFIED>
J 0
(-2235 6940);
DISPLAY 0.978723 (-2235 6940);
FORCEPROP 2 LAST CUSTOM_TXT_CDS <XR_PAGE_TITLE>
J 0
(-8240 12175);
DISPLAY 0.638298 (-8240 12175);
PAINT PINK (-8240 12175);
DISPLAY INVISIBLE (-8240 12175);
FORCEPROP 1 LAST CUSTOM_TXT_CDS <NAME_2>
J 0
(-3525 6975);
FORCEPROP 1 LAST CUSTOM_TXT_CDS <NAME_1>
J 0
(-3525 7100);
FORCEPROP 1 LAST CUSTOM_TXT_CDS <Q_NUMBER>
J 0
(-1753 7028);
DISPLAY 1.212766 (-1753 7028);
FORCEPROP 1 LAST CUSTOM_TXT_CDS <Q_PROJ>
J 0
(-2732 7027);
DISPLAY 1.212766 (-2732 7027);
FORCEPROP 1 LAST CUSTOM_TXT_CDS <Q_REV>
J 0
(-534 7028);
DISPLAY 1.212766 (-534 7028);
FORCEPROP 1 LAST CUSTOM_TXT_CDS <CON_PAGE_NUM> OF <CON_TOTAL_PAGES>
J 0
(-796 6943);
DISPLAY 0.978723 (-796 6943);
FORCEPROP 1 LAST Q_TITLE VCCINFAON CPU1 VR PHASE 1&2 (2/3)
J 0
(-9650 6975);
DISPLAY 2.446809 (-9650 6975);
PAINT GREEN (-9650 6975);
FORCEPROP 1 LAST Q_DEPT 
J 1
(-4113 6974);
DISPLAY 1.957447 (-4113 6974);
PAINT GREEN (-4113 6974);
FORCEPROP 2 LAST CDS_XR_PAGE_TITLE CR-293 : @S9S_MB_2U_LIB.S9S_MB_2U(SCH_1):PAGE293
J 0
(-8240 12175);
DISPLAY 0.638298 (-8240 12175);
PAINT PINK (-8240 12175);
DISPLAY INVISIBLE (-8240 12175);
FORCEPROP 2 LAST PAGE_BORDER TRUE
J 0
(-8240 12175);
DISPLAY 0.638298 (-8240 12175);
PAINT PINK (-8240 12175);
DISPLAY INVISIBLE (-8240 12175);
FORCEPROP 1 LAST CDS_LMAN_SYM_OUTLINE -9475,6775,100,-125
J 0
(-350 6925);
DISPLAY 0.468085 (-350 6925);
PAINT GREEN (-350 6925);
DISPLAY INVISIBLE (-350 6925);
FORCEPROP 2 LAST CDS_LIB pure_quanta
J 0
(-350 6925);
DISPLAY INVISIBLE (-350 6925);
FORCEPROP 1 LAST COMMENT_BODY TRUE
J 0
(-338 6912);
DISPLAY 0.978723 (-338 6912);
PAINT GREEN (-338 6912);
DISPLAY INVISIBLE (-338 6912);
WIRE 16 -1 (-8500 9675)(-8500 9525);
WIRE 16 -1 (-8500 9525)(-7975 9525);
FORCEPROP 0 LAST SIG_NAME PVCCFA_EHV_CPU1_PVCC
J 0
(-8460 9560);
DISPLAY 0.659574 (-8460 9560);
FORCEPROP 2 LASTPROP $XR2 297 
J 0
(-8856 9560);
DISPLAY 0.638298 (-8856 9560);
PAINT MONO (-8856 9560);
FORCEPROP 2 LASTPROP $XR1 294 
J 0
(-8736 9560);
DISPLAY 0.638298 (-8736 9560);
PAINT MONO (-8736 9560);
FORCEPROP 2 LASTPROP $XR0 293 
J 0
(-8616 9560);
DISPLAY 0.638298 (-8616 9560);
PAINT MONO (-8616 9560);
WIRE 16 -1 (-8500 12425)(-8500 12325);
WIRE 16 -1 (-8500 12325)(-7925 12325);
FORCEPROP 0 LAST SIG_NAME PVCCFA_EHV_CPU1_PVCC
J 0
(-8460 12360);
DISPLAY 0.659574 (-8460 12360);
FORCEPROP 2 LASTPROP $XR2 297 
J 0
(-8856 12360);
DISPLAY 0.638298 (-8856 12360);
PAINT MONO (-8856 12360);
FORCEPROP 2 LASTPROP $XR1 294 
J 0
(-8736 12360);
DISPLAY 0.638298 (-8736 12360);
PAINT MONO (-8736 12360);
FORCEPROP 2 LASTPROP $XR0 293 
J 0
(-8616 12360);
DISPLAY 0.638298 (-8616 12360);
PAINT MONO (-8616 12360);
WIRE 16 -1 (-4375 9650)(-4375 9575);
WIRE 16 -1 (-4375 12450)(-4375 12375);
WIRE 16 -1 (-2425 8525)(-2425 8425);
WIRE 16 -1 (-2800 11375)(-2800 11225);
WIRE 16 -1 (-725 9500)(-725 9450);
WIRE 16 -1 (-725 10425)(-725 10375);
WIRE 16 -1 (-3125 12675)(-3125 12550);
WIRE 16 -1 (-775 12625)(-775 12550);
WIRE 16 -1 (-9000 7750)(-9000 7675);
WIRE 16 -1 (-9150 8250)(-9150 8200);
WIRE 16 -1 (-9150 8250)(-8425 8250);
WIRE 16 -1 (-8500 8775)(-8500 8675);
WIRE 16 -1 (-7975 9200)(-7975 9150);
WIRE 16 -1 (-9000 10550)(-9000 10475);
WIRE 16 -1 (-9150 11050)(-9150 11000);
WIRE 16 -1 (-9150 11050)(-8425 11050);
WIRE 16 -1 (-8500 11575)(-8500 11475);
WIRE 16 -1 (-7925 11950)(-7925 11925);
WIRE 16 -1 (-6325 7825)(-6325 7750);
WIRE 16 -1 (-6325 7875)(-6325 7825);
WIRE 16 -1 (-6575 7825)(-6325 7825);
WIRE 16 -1 (-2425 7900)(-2425 8000);
WIRE 16 -1 (-6325 10625)(-6325 10550);
WIRE 16 -1 (-6325 10675)(-6325 10625);
WIRE 16 -1 (-6575 10625)(-6325 10625);
WIRE 16 -1 (-4375 8950)(-4375 9075);
WIRE 16 -1 (-4375 11750)(-4375 11875);
WIRE 16 -1 (-2800 10700)(-2800 10800);
WIRE 16 -1 (-3125 12150)(-3125 12250);
WIRE 16 -1 (-725 9000)(-725 8950);
WIRE 16 -1 (-1325 9000)(-725 9000);
WIRE 16 -1 (-725 9925)(-725 9875);
WIRE 16 -1 (-1900 9925)(-725 9925);
WIRE 16 -1 (-775 12075)(-775 12150);
WIRE 16 -1 (-2375 12250)(-2375 12150);
WIRE 16 -1 (-2375 12150)(-1975 12150);
WIRE 16 -1 (-1975 12250)(-1975 12150);
WIRE 16 -1 (-775 12150)(-1975 12150);
WIRE 16 -1 (-2375 12550)(-2600 12550);
WIRE 16 -1 (-2375 12550)(-2375 12450);
WIRE 16 -1 (-2375 12550)(-1975 12550);
WIRE 16 -1 (-1975 12450)(-1975 12550);
WIRE 16 -1 (-775 12550)(-1975 12550);
WIRE 16 -1 (-1325 9125)(-1325 9000);
WIRE 16 -1 (-1900 9000)(-1900 9125);
WIRE 16 -1 (-1900 9000)(-1325 9000);
WIRE 16 -1 (-2475 9000)(-1900 9000);
WIRE 16 -1 (-2475 9125)(-2475 9000);
WIRE 16 -1 (-1325 9325)(-1325 9450);
WIRE 16 -1 (-725 9450)(-1325 9450);
WIRE 16 -1 (-1900 9450)(-1900 9325);
WIRE 16 -1 (-1900 9450)(-1325 9450);
WIRE 16 -1 (-2475 9450)(-1900 9450);
WIRE 16 -1 (-2475 9325)(-2475 9450);
WIRE 16 -1 (-3125 12450)(-3125 12550);
WIRE 16 -1 (-3125 12550)(-2800 12550);
WIRE 16 -1 (-1900 10375)(-1900 10250);
WIRE 16 -1 (-1900 10375)(-725 10375);
WIRE 16 -1 (-2475 10375)(-1900 10375);
WIRE 16 -1 (-2475 10250)(-2475 10375);
WIRE 16 -1 (-2475 10050)(-2475 9925);
WIRE 16 -1 (-2475 9925)(-1900 9925);
WIRE 16 -1 (-1900 9925)(-1900 10050);
WIRE 16 -1 (-3100 11125)(-3100 11225);
WIRE 16 -1 (-2800 11225)(-3100 11225);
WIRE 16 -1 (-3525 11225)(-3525 11125);
WIRE 16 -1 (-3525 11225)(-3100 11225);
WIRE 16 -1 (-3925 11125)(-3925 11225);
WIRE 16 -1 (-3925 11225)(-3525 11225);
WIRE 16 -1 (-4175 11225)(-4475 11225);
WIRE 16 -1 (-3925 11225)(-4175 11225);
WIRE 16 -1 (-4175 11225)(-4175 10975);
WIRE 16 -1 (-5150 10975)(-4175 10975);
WIRE 16 -1 (-3100 10925)(-3100 10800);
WIRE 16 -1 (-2800 10800)(-3100 10800);
WIRE 16 -1 (-3525 10800)(-3525 10925);
WIRE 16 -1 (-3100 10800)(-3525 10800);
WIRE 16 -1 (-3925 10800)(-3525 10800);
WIRE 16 -1 (-3925 10925)(-3925 10800);
WIRE 16 -1 (-2800 8425)(-2800 8325);
WIRE 16 -1 (-2425 8425)(-2800 8425);
WIRE 16 -1 (-3275 8325)(-3275 8425);
WIRE 16 -1 (-2800 8425)(-3275 8425);
WIRE 16 -1 (-3700 8425)(-3700 8325);
WIRE 16 -1 (-3700 8425)(-3275 8425);
WIRE 16 -1 (-4475 8425)(-4075 8425);
WIRE 16 -1 (-4075 8425)(-3700 8425);
WIRE 16 -1 (-4075 8425)(-4075 8175);
WIRE 16 -1 (-5175 8175)(-4075 8175);
WIRE 16 -1 (-4975 12225)(-4975 12375);
WIRE 16 -1 (-4975 12375)(-4375 12375);
WIRE 16 -1 (-5375 12375)(-5375 12225);
WIRE 16 -1 (-5375 12375)(-4975 12375);
WIRE 16 -1 (-5775 12225)(-5775 12375);
WIRE 16 -1 (-5775 12375)(-5375 12375);
WIRE 16 -1 (-6175 12225)(-6175 12375);
WIRE 16 -1 (-6175 12375)(-5775 12375);
WIRE 16 -1 (-6400 12375)(-6175 12375);
WIRE 16 -1 (-6575 11875)(-6400 11875);
WIRE 16 -1 (-6400 12375)(-6400 11875);
WIRE 16 -1 (-6400 11825)(-6400 11875);
WIRE 16 -1 (-6575 11825)(-6400 11825);
WIRE 16 -1 (-4975 12025)(-4975 11875);
WIRE 16 -1 (-4975 11875)(-4375 11875);
WIRE 16 -1 (-5375 12025)(-5375 11875);
WIRE 16 -1 (-5375 11875)(-4975 11875);
WIRE 16 -1 (-5775 12025)(-5775 11875);
WIRE 16 -1 (-5375 11875)(-5775 11875);
WIRE 16 -1 (-6175 11875)(-5775 11875);
WIRE 16 -1 (-6175 12025)(-6175 11875);
WIRE 16 -1 (-4800 11675)(-4800 11600);
WIRE 16 -1 (-5525 11675)(-4800 11675);
FORCEPROP 2 LAST SIG_NAME SW_PVCCINFAON_CPU1_BOOT1_R
J 0
(-5335 11685);
DISPLAY 0.617021 (-5335 11685);
WIRE 16 -1 (-4975 9075)(-4375 9075);
WIRE 16 -1 (-4975 9225)(-4975 9075);
WIRE 16 -1 (-5375 9225)(-5375 9075);
WIRE 16 -1 (-5375 9075)(-4975 9075);
WIRE 16 -1 (-5375 9075)(-5775 9075);
WIRE 16 -1 (-5775 9225)(-5775 9075);
WIRE 16 -1 (-6175 9075)(-5775 9075);
WIRE 16 -1 (-6175 9225)(-6175 9075);
WIRE 16 -1 (-4975 9425)(-4975 9575);
WIRE 16 -1 (-4975 9575)(-4375 9575);
WIRE 16 -1 (-5375 9575)(-5375 9425);
WIRE 16 -1 (-5375 9575)(-4975 9575);
WIRE 16 -1 (-5775 9425)(-5775 9575);
WIRE 16 -1 (-5775 9575)(-5375 9575);
WIRE 16 -1 (-6175 9425)(-6175 9575);
WIRE 16 -1 (-6175 9575)(-5775 9575);
WIRE 16 -1 (-6400 9575)(-6175 9575);
WIRE 16 -1 (-6575 9075)(-6400 9075);
WIRE 16 -1 (-6400 9575)(-6400 9075);
WIRE 16 -1 (-6400 9025)(-6400 9075);
WIRE 16 -1 (-6575 9025)(-6400 9025);
WIRE 16 -1 (-4800 8875)(-4800 8800);
WIRE 16 -1 (-5525 8875)(-4800 8875);
FORCEPROP 2 LAST SIG_NAME SW_PVCCINFAON_CPU1_BOOT2_R
J 0
(-5335 8885);
DISPLAY 0.617021 (-5335 8885);
WIRE 16 -1 (-6575 11225)(-4675 11225);
FORCEPROP 2 LAST SIG_NAME SW_PVCCINFAON_CPU1_SW1
J 0
(-6385 11235);
DISPLAY 0.617021 (-6385 11235);
WIRE 16 -1 (-6575 10975)(-5350 10975);
FORCEPROP 2 LAST SIG_NAME PVCCINFAON_CPU1_VOS1
J 0
(-6385 11010);
DISPLAY 0.638298 (-6385 11010);
WIRE 16 -1 (-6575 8425)(-4675 8425);
FORCEPROP 2 LAST SIG_NAME SW_PVCCINFAON_CPU1_SW2
J 0
(-6385 8435);
DISPLAY 0.617021 (-6385 8435);
WIRE 16 -1 (-4800 8525)(-4800 8600);
WIRE 16 -1 (-6575 8525)(-4800 8525);
FORCEPROP 0 LAST CDS_PHYS_NET_NAME SW_PVCCINFAON_CPU1_BOOTR2
J 0
(-6385 8565);
PAINT MONO (-6385 8565);
DISPLAY INVISIBLE (-6385 8565);
FORCEPROP 2 LAST SIG_NAME SW_PVCCINFAON_CPU1_BOOTR2
J 0
(-6385 8535);
DISPLAY 0.617021 (-6385 8535);
WIRE 16 -1 (-4800 11325)(-4800 11400);
WIRE 16 -1 (-6575 11325)(-4800 11325);
FORCEPROP 0 LAST CDS_PHYS_NET_NAME SW_PVCCINFAON_CPU1_BOOTR1
J 0
(-6385 11365);
PAINT MONO (-6385 11365);
DISPLAY INVISIBLE (-6385 11365);
FORCEPROP 2 LAST SIG_NAME SW_PVCCINFAON_CPU1_BOOTR1
J 0
(-6385 11335);
DISPLAY 0.617021 (-6385 11335);
WIRE 16 -1 (-6425 11675)(-5725 11675);
FORCEPROP 0 LAST CDS_PHYS_NET_NAME SW_PVCCINFAON_CPU1_BOOT1
J 0
(-6385 11704);
PAINT MONO (-6385 11704);
DISPLAY INVISIBLE (-6385 11704);
WIRE 16 -1 (-6425 11575)(-6425 11675);
FORCEPROP 2 LAST SIG_NAME SW_PVCCINFAON_CPU1_BOOT1
J 0
(-6610 11685);
DISPLAY 0.617021 (-6610 11685);
WIRE 16 -1 (-6575 11575)(-6425 11575);
WIRE 16 -1 (-6575 10675)(-6325 10675);
WIRE 16 -1 (-6575 10725)(-6325 10725);
WIRE 16 -1 (-6325 10675)(-6325 10725);
WIRE 16 -1 (-6325 10725)(-6325 10775);
WIRE 16 -1 (-6325 10775)(-6575 10775);
WIRE 16 -1 (-8500 12175)(-8500 12325);
WIRE 16 -1 (-7550 11875)(-7425 11875);
WIRE 16 -1 (-7550 12325)(-7550 11875);
WIRE 16 -1 (-7925 12150)(-7925 12325);
WIRE 16 -1 (-7925 12325)(-7550 12325);
WIRE 16 -1 (-7575 11375)(-7425 11375);
WIRE 16 -1 (-7575 11375)(-7575 11575);
WIRE 16 -1 (-7425 11575)(-7575 11575);
WIRE 16 -1 (-8125 11575)(-7575 11575);
WIRE 16 -1 (-8125 11575)(-8125 11875);
WIRE 16 -1 (-8500 11875)(-8500 11775);
WIRE 16 -1 (-8500 11975)(-8500 11875);
WIRE 16 -1 (-8500 11875)(-8125 11875);
FORCEPROP 2 LAST SIG_NAME PVCCINFAON_CPU1_VDD1
J 0
(-8110 11610);
DISPLAY 0.617021 (-8110 11610);
WIRE 16 -1 (-6425 8875)(-5725 8875);
FORCEPROP 0 LAST CDS_PHYS_NET_NAME SW_PVCCINFAON_CPU1_BOOT2
J 0
(-6385 8904);
PAINT MONO (-6385 8904);
DISPLAY INVISIBLE (-6385 8904);
WIRE 16 -1 (-6425 8775)(-6425 8875);
FORCEPROP 2 LAST SIG_NAME SW_PVCCINFAON_CPU1_BOOT2
J 0
(-6610 8885);
DISPLAY 0.617021 (-6610 8885);
WIRE 16 -1 (-6575 8775)(-6425 8775);
WIRE 16 -1 (-7600 9075)(-7425 9075);
WIRE 16 -1 (-7600 9525)(-7600 9075);
WIRE 16 -1 (-8500 9375)(-8500 9525);
WIRE 16 -1 (-7600 9525)(-7975 9525);
WIRE 16 -1 (-7975 9400)(-7975 9525);
WIRE 16 -1 (-7425 8575)(-7500 8575);
WIRE 16 -1 (-7500 8575)(-7500 8775);
WIRE 16 -1 (-7425 8775)(-7500 8775);
WIRE 16 -1 (-7500 8775)(-8075 8775);
WIRE 16 -1 (-8075 8775)(-8075 9075);
WIRE 16 -1 (-8500 9075)(-8500 8975);
WIRE 16 -1 (-8500 9075)(-8075 9075);
FORCEPROP 2 LAST SIG_NAME PVCCINFAON_CPU1_VDD2
J 0
(-8060 8810);
DISPLAY 0.617021 (-8060 8810);
WIRE 16 -1 (-8500 9175)(-8500 9075);
WIRE 16 -1 (-3700 8000)(-3700 8125);
WIRE 16 -1 (-3275 8000)(-3700 8000);
WIRE 16 -1 (-3275 8125)(-3275 8000);
WIRE 16 -1 (-2800 8000)(-3275 8000);
WIRE 16 -1 (-2800 8125)(-2800 8000);
WIRE 16 -1 (-2425 8000)(-2800 8000);
WIRE 16 -1 (-6575 8175)(-5375 8175);
FORCEPROP 0 LAST SIG_NAME PVCCINFAON_CPU1_VOS2
J 0
(-6410 8185);
DISPLAY 0.617021 (-6410 8185);
WIRE 16 -1 (-6575 7875)(-6325 7875);
WIRE 16 -1 (-6325 7975)(-6575 7975);
WIRE 16 -1 (-6575 7925)(-6325 7925);
WIRE 16 -1 (-6325 7875)(-6325 7925);
WIRE 16 -1 (-6325 7925)(-6325 7975);
WIRE 16 -1 (-7425 7825)(-8375 7825);
FORCEPROP 2 LAST SIG_NAME PVCCINFAON_CPU1_APWM2
J 0
(-8260 7835);
DISPLAY 0.617021 (-8260 7835);
WIRE 16 -1 (-7425 11225)(-8375 11225);
FORCEPROP 2 LAST SIG_NAME PVCCINFAON_CPU1_ACSP1
J 0
(-8260 11235);
DISPLAY 0.617021 (-8260 11235);
WIRE 16 -1 (-7675 11050)(-8225 11050);
WIRE 16 -1 (-8375 11125)(-7675 11125);
FORCEPROP 2 LAST SIG_NAME PVCCINFAON_CPU1_VREF
J 0
(-8260 11135);
DISPLAY 0.617021 (-8260 11135);
WIRE 16 -1 (-7675 11125)(-7425 11125);
WIRE 16 -1 (-7675 11125)(-7675 11050);
FORCEPROP 0 LAST CDS_PHYS_NET_NAME PVCCINFAON_CPU1_VREF
J 0
(-7675 11075);
PAINT MONO (-7675 11075);
DISPLAY INVISIBLE (-7675 11075);
WIRE 16 -1 (-7425 10725)(-8375 10725);
FORCEPROP 2 LAST SIG_NAME PVCCINFAON_CPU1_ATSEN
J 0
(-8260 10735);
DISPLAY 0.617021 (-8260 10735);
WIRE 16 -1 (-7425 10625)(-8375 10625);
FORCEPROP 2 LAST SIG_NAME PVCCINFAON_CPU1_APWM1
J 0
(-8260 10635);
DISPLAY 0.617021 (-8260 10635);
WIRE 16 -1 (-7425 8425)(-8375 8425);
FORCEPROP 2 LAST SIG_NAME PVCCINFAON_CPU1_ACSP2
J 0
(-8260 8435);
DISPLAY 0.617021 (-8260 8435);
WIRE 16 -1 (-7675 8250)(-8225 8250);
WIRE 16 -1 (-8375 8325)(-7675 8325);
FORCEPROP 2 LAST SIG_NAME PVCCINFAON_CPU1_VREF
J 0
(-8260 8335);
DISPLAY 0.617021 (-8260 8335);
WIRE 16 -1 (-7675 8325)(-7425 8325);
WIRE 16 -1 (-7675 8325)(-7675 8250);
FORCEPROP 0 LAST CDS_PHYS_NET_NAME PVCCINFAON_CPU1_VREF
J 0
(-7675 8275);
PAINT MONO (-7675 8275);
DISPLAY INVISIBLE (-7675 8275);
WIRE 16 -1 (-7425 7925)(-8375 7925);
FORCEPROP 2 LAST SIG_NAME PVCCINFAON_CPU1_ATSEN
J 0
(-8260 7935);
DISPLAY 0.617021 (-8260 7935);
WIRE 16 -1 (-9000 10925)(-9000 10750);
WIRE 16 -1 (-9000 10925)(-7425 10925);
FORCEPROP 2 LAST SIG_NAME PVCCINFAON_CPU1_LSET1
J 0
(-8260 10935);
DISPLAY 0.617021 (-8260 10935);
WIRE 16 -1 (-9000 8125)(-9000 7950);
WIRE 16 -1 (-7425 8125)(-9000 8125);
FORCEPROP 2 LAST SIG_NAME PVCCINFAON_CPU1_LSET2
J 0
(-8285 8135);
DISPLAY 0.617021 (-8285 8135);
DOT 1 (-8500 9075);
DOT 1 (-8500 9525);
DOT 1 (-7975 9525);
DOT 1 (-8500 11875);
DOT 1 (-8500 12325);
DOT 1 (-7925 12325);
DOT 1 (-6325 7825);
DOT 1 (-6325 7875);
DOT 1 (-6325 7925);
DOT 1 (-3275 8000);
DOT 1 (-2800 8000);
DOT 1 (-7675 8325);
DOT 1 (-7500 8775);
DOT 1 (-6400 9075);
DOT 1 (-5775 9075);
DOT 1 (-6175 9575);
DOT 1 (-5775 9575);
DOT 1 (-7675 11125);
DOT 1 (-7575 11575);
DOT 1 (-6325 10625);
DOT 1 (-6325 10675);
DOT 1 (-6325 10725);
DOT 1 (-6400 11875);
DOT 1 (-5775 11875);
DOT 1 (-5375 9075);
DOT 1 (-4975 9075);
DOT 1 (-5375 9575);
DOT 1 (-4975 9575);
DOT 1 (-4075 8425);
DOT 1 (-5375 11875);
DOT 1 (-4975 11875);
DOT 1 (-4175 11225);
DOT 1 (-3925 11225);
DOT 1 (-6175 12375);
DOT 1 (-5775 12375);
DOT 1 (-5375 12375);
DOT 1 (-4975 12375);
DOT 1 (-3700 8425);
DOT 1 (-3275 8425);
DOT 1 (-2800 8425);
DOT 1 (-1900 9000);
DOT 1 (-1900 9450);
DOT 1 (-1900 9925);
DOT 1 (-3525 10800);
DOT 1 (-3525 11225);
DOT 1 (-3100 10800);
DOT 1 (-3100 11225);
DOT 1 (-1900 10375);
DOT 1 (-1975 12150);
DOT 1 (-1325 9000);
DOT 1 (-1325 9450);
DOT 1 (-3125 12550);
DOT 1 (-2375 12550);
DOT 1 (-1975 12550);
FORCENOTE
APPLY TO ALL RAILS.
(-3225 7475) 0;
DISPLAY LEFT (-3225 7475);
DISPLAY 1.021277 (-3225 7475);
FORCENOTE
(499OHM) TO ABSORB LEAKAGE FROM SPS.
(-3225 7550) 0;
DISPLAY LEFT (-3225 7550);
DISPLAY 1.021277 (-3225 7550);
FORCENOTE
RENESAS RECOMMEND BLEEDER RESISTOR
(-3225 7625) 0;
DISPLAY LEFT (-3225 7625);
DISPLAY 1.021277 (-3225 7625);
FORCENOTE
PVCCINFAON_CPU1_PHASE2
(-7475 9725) 0;
DISPLAY LEFT (-7475 9725);
DISPLAY 1.021277 (-7475 9725);
PAINT WHITE (-7475 9725);
FORCENOTE
PVCCINFAON_CPU1_PHASE1
(-7475 12525) 0;
DISPLAY LEFT (-7475 12525);
DISPLAY 1.021277 (-7475 12525);
PAINT WHITE (-7475 12525);
FORCENOTE
PGL6312.121AHLT 
(-4275 8725) 0;
DISPLAY LEFT (-4275 8725);
DISPLAY 1.021277 (-4275 8725);
FORCENOTE
6.5*6.5*10.0
(-4275 8650) 0;
DISPLAY LEFT (-4275 8650);
DISPLAY 1.021277 (-4275 8650);
FORCENOTE
ISAT=60A@100C
(-4275 8575) 0;
DISPLAY LEFT (-4275 8575);
DISPLAY 1.021277 (-4275 8575);
FORCENOTE
DCR=0.17M OHM
(-4275 8500) 0;
DISPLAY LEFT (-4275 8500);
DISPLAY 1.021277 (-4275 8500);
FORCENOTE
PGL6312.121AHLT 
(-4275 11550) 0;
DISPLAY LEFT (-4275 11550);
DISPLAY 1.021277 (-4275 11550);
FORCENOTE
DCR=0.17M OHM
(-4275 11325) 0;
DISPLAY LEFT (-4275 11325);
DISPLAY 1.021277 (-4275 11325);
FORCENOTE
ISAT=60A@100C
(-4275 11400) 0;
DISPLAY LEFT (-4275 11400);
DISPLAY 1.021277 (-4275 11400);
FORCENOTE
6.5*6.5*10.0
(-4275 11475) 0;
DISPLAY LEFT (-4275 11475);
DISPLAY 1.021277 (-4275 11475);
FORCENOTE
ESR=9.5M OHM
(-2350 12100) 0;
DISPLAY LEFT (-2350 12100);
DISPLAY 0.638298 (-2350 12100);
FORCENOTE
ESR=9.5M OHM
(-1925 12100) 0;
DISPLAY LEFT (-1925 12100);
DISPLAY 0.638298 (-1925 12100);
FORCENOTE
4.5*4.5*4.5
(-2425 12775) 0;
DISPLAY LEFT (-2425 12775);
DISPLAY 0.808511 (-2425 12775);
FORCENOTE
HCBS4545-101
(-2425 12850) 0;
DISPLAY LEFT (-2425 12850);
DISPLAY 0.808511 (-2425 12850);
FORCENOTE
ISAT = 13A @ 100C
(-2425 12700) 0;
DISPLAY LEFT (-2425 12700);
DISPLAY 0.808511 (-2425 12700);
FORCENOTE
DCR = 0.12M OHM
(-2425 12625) 0;
DISPLAY LEFT (-2425 12625);
DISPLAY 0.808511 (-2425 12625);
QUIT
